FILE_TYPE = MACRO_DRAWING;
SET COLOR_WIRE YELLOW;
SET COLOR_PROP ORANGE;
SET COLOR_DOT WHITE;
SET COLOR_ARC YELLOW;
SET COLOR_BODY GREEN;
SET COLOR_NOTE PURPLE;
SET PROP_DISPLAY VALUE;
SET PAGE_NUMBER P345;
FORCEADD OFFPAGE..1
(6100 -425);
FORCEPROP 2 LAST $XR0 144 
J 0
(5848 -425);
DISPLAY 0.638298 (5848 -425);
PAINT MONO (5848 -425);
FORCEPROP 2 LAST $XR1 82 
J 0
(5758 -425);
DISPLAY 0.638298 (5758 -425);
PAINT MONO (5758 -425);
FORCEPROP 2 LASTPIN (6150 -425) SIG_NAME M2_SSD0_CLKREQ_EN_N
J 0
(6190 -415);
DISPLAY 0.808511 (6190 -415);
PAINT WHITE (6190 -415);
FORCEPROP 2 LAST PATH I1
J 0
(5825 -375);
DISPLAY 0.680851 (5825 -375);
DISPLAY INVISIBLE (5825 -375);
FORCEPROP 1 LAST COMMENT_BODY TRUE
J 0
(6225 -525);
DISPLAY 0.872340 (6225 -525);
PAINT GREEN (6225 -525);
DISPLAY INVISIBLE (6225 -525);
FORCEPROP 1 LAST OFFPAGE TRUE
J 0
(6425 -550);
DISPLAY 0.872340 (6425 -550);
PAINT AQUA (6425 -550);
DISPLAY INVISIBLE (6425 -550);
FORCEPROP 2 LAST CDS_LIB standard
J 0
(6100 -425);
DISPLAY INVISIBLE (6100 -425);
FORCEADD Q_RES..2
(10675 -325);
FORCEPROP 1 LAST LOCATION R2121
J 0
(10720 -200);
DISPLAY 0.638298 (10720 -200);
FORCEPROP 0 LAST $SEC 1
J 0
(10725 -150);
DISPLAY 0.680851 (10725 -150);
PAINT MONO (10725 -150);
DISPLAY INVISIBLE (10725 -150);
FORCEPROP 0 LAST CDS_SEC 1
J 0
(10725 -150);
DISPLAY 1.021277 (10725 -150);
DISPLAY INVISIBLE (10725 -150);
FORCEPROP 1 LASTPIN (10675 -225) $PN 1
J 0
(10680 -263);
DISPLAY 0.787234 (10680 -263);
PAINT MONO (10680 -263);
FORCEPROP 1 LASTPIN (10675 -425) $PN 2
J 0
(10680 -415);
DISPLAY 0.787234 (10680 -415);
PAINT MONO (10680 -415);
FORCEPROP 1 LAST VALUE 4.7K
J 0
(10720 -250);
DISPLAY 0.638298 (10720 -250);
FORCEPROP 1 LAST MATERIAL CHIP
J 0
(10715 -400);
DISPLAY 0.638298 (10715 -400);
FORCEPROP 1 LAST TOLERANCE 5%
J 0
(10720 -300);
DISPLAY 0.638298 (10720 -300);
FORCEPROP 1 LAST WATTAGE 1/16W
J 0
(10715 -350);
DISPLAY 0.638298 (10715 -350);
FORCEPROP 1 LAST PACK_TYPE 0402LF
J 0
(10725 -450);
DISPLAY 0.638298 (10725 -450);
FORCEPROP 1 LAST PART_NUMBER CS24702JB10
J 0
(10715 -450);
DISPLAY 0.638298 (10715 -450);
DISPLAY INVISIBLE (10715 -450);
FORCEPROP 1 LAST PATH I10
J 0
(10725 -150);
DISPLAY 0.978723 (10725 -150);
PAINT WHITE (10725 -150);
DISPLAY INVISIBLE (10725 -150);
FORCEPROP 2 LAST CDS_LIB pure_quanta
J 0
(10675 -325);
DISPLAY INVISIBLE (10675 -325);
FORCEADD UNIVERSAL_POWER..1
(10675 -100);
FORCEPROP 3 LASTPIN (10675 -150) SIG_NAME P3V3_AUX\g
J 0
(10685 -140);
DISPLAY 0.659574 (10685 -140);
PAINT MONO (10685 -140);
DISPLAY INVISIBLE (10685 -140);
FORCEPROP 1 LAST HDL_POWER P3V3_AUX
J 1
(10675 -50);
DISPLAY 0.872340 (10675 -50);
PAINT GREEN (10675 -50);
FORCEPROP 1 LAST PATH I11
J 0
(10725 -75);
DISPLAY 0.872340 (10725 -75);
PAINT AQUA (10725 -75);
DISPLAY INVISIBLE (10725 -75);
FORCEPROP 2 LAST CDS_LIB pure_quanta_power
J 0
(10675 -100);
DISPLAY INVISIBLE (10675 -100);
FORCEADD Q_RES..1
(11100 -525);
FORCEPROP 1 LAST LOCATION R2113
J 0
(10875 -525);
DISPLAY 0.638298 (10875 -525);
FORCEPROP 0 LAST $SEC 1
J 0
(11225 -425);
DISPLAY 0.680851 (11225 -425);
PAINT MONO (11225 -425);
DISPLAY INVISIBLE (11225 -425);
FORCEPROP 0 LAST CDS_SEC 1
J 0
(11225 -425);
DISPLAY 1.021277 (11225 -425);
DISPLAY INVISIBLE (11225 -425);
FORCEPROP 1 LASTPIN (11000 -525) $PN 1
J 0
(11012 -513);
DISPLAY 0.787234 (11012 -513);
PAINT MONO (11012 -513);
FORCEPROP 1 LASTPIN (11200 -525) $PN 2
J 0
(11162 -513);
DISPLAY 0.787234 (11162 -513);
PAINT MONO (11162 -513);
FORCEPROP 1 LAST MATERIAL CHIP
J 0
(11350 -525);
DISPLAY 0.510638 (11350 -525);
FORCEPROP 1 LAST TOLERANCE 5%
J 0
(11275 -525);
DISPLAY 0.510638 (11275 -525);
FORCEPROP 1 LAST VALUE 0
J 2
(11250 -525);
DISPLAY 0.510638 (11250 -525);
FORCEPROP 1 LAST WATTAGE 1/16W
J 2
(11225 -450);
DISPLAY 0.404255 (11225 -450);
FORCEPROP 1 LAST PACK_TYPE 0402LF
J 0
(11000 -450);
DISPLAY 0.404255 (11000 -450);
FORCEPROP 1 LAST PART_NUMBER CS00002JB13
J 0
(11000 -475);
DISPLAY 0.404255 (11000 -475);
DISPLAY INVISIBLE (11000 -475);
FORCEPROP 1 LAST PATH I12
J 0
(11050 -375);
DISPLAY 0.978723 (11050 -375);
PAINT WHITE (11050 -375);
DISPLAY INVISIBLE (11050 -375);
FORCEPROP 2 LAST CDS_LIB pure_quanta
J 0
(11100 -525);
DISPLAY INVISIBLE (11100 -525);
FORCEADD OFFPAGE..2
(12475 -525);
FORCEPROP 2 LAST $XR0 144 
J 0
(12664 -525);
DISPLAY 0.638298 (12664 -525);
PAINT MONO (12664 -525);
FORCEPROP 2 LAST PATH I13
J 0
(12675 -475);
DISPLAY 0.680851 (12675 -475);
DISPLAY INVISIBLE (12675 -475);
FORCEPROP 1 LAST COMMENT_BODY TRUE
J 0
(12430 -620);
DISPLAY 0.872340 (12430 -620);
PAINT GREEN (12430 -620);
DISPLAY INVISIBLE (12430 -620);
FORCEPROP 1 LAST OFFPAGE TRUE
J 0
(12800 -650);
DISPLAY 0.872340 (12800 -650);
PAINT GREEN (12800 -650);
DISPLAY INVISIBLE (12800 -650);
FORCEPROP 2 LAST CDS_LIB standard
J 0
(12475 -525);
PAINT MONO (12475 -525);
DISPLAY INVISIBLE (12475 -525);
FORCEADD UNIVERSAL_GND..1
(5400 2775);
FORCEPROP 3 LASTPIN (5400 2825) SIG_NAME GND\g
J 0
(5410 2835);
DISPLAY 0.659574 (5410 2835);
PAINT MONO (5410 2835);
DISPLAY INVISIBLE (5410 2835);
FORCEPROP 1 LAST PATH I14
J 0
(5475 2775);
DISPLAY 0.872340 (5475 2775);
PAINT AQUA (5475 2775);
DISPLAY INVISIBLE (5475 2775);
FORCEPROP 1 LAST HDL_POWER GND
J 1
(5425 2700);
DISPLAY 0.872340 (5425 2700);
PAINT GREEN (5425 2700);
DISPLAY INVISIBLE (5425 2700);
FORCEPROP 2 LAST CDS_LIB pure_quanta_power
J 0
(5400 2775);
PAINT MONO (5400 2775);
DISPLAY INVISIBLE (5400 2775);
FORCEADD Q_RES..2
(5400 3000);
FORCEPROP 1 LAST LOCATION R138
J 0
(5445 3125);
DISPLAY 0.978723 (5445 3125);
FORCEPROP 2 LAST $SEC 1
J 0
(5450 3225);
DISPLAY 0.680851 (5450 3225);
PAINT MONO (5450 3225);
DISPLAY INVISIBLE (5450 3225);
FORCEPROP 2 LAST CDS_SEC 1
J 0
(5450 3225);
DISPLAY 1.021277 (5450 3225);
DISPLAY INVISIBLE (5450 3225);
FORCEPROP 1 LASTPIN (5400 3100) $PN 1
J 0
(5405 3062);
DISPLAY 0.787234 (5405 3062);
FORCEPROP 1 LASTPIN (5400 2900) $PN 2
J 0
(5405 2910);
DISPLAY 0.787234 (5405 2910);
FORCEPROP 1 LAST PACK_TYPE 0402LF
J 0
(5440 2825);
DISPLAY 0.638298 (5440 2825);
FORCEPROP 1 LAST WATTAGE 1/16W
J 0
(5440 2975);
DISPLAY 0.638298 (5440 2975);
FORCEPROP 1 LAST TOLERANCE 1%
J 0
(5445 3025);
DISPLAY 0.638298 (5445 3025);
FORCEPROP 1 LAST MATERIAL EMPTY
J 0
(5440 2925);
DISPLAY 0.638298 (5440 2925);
PAINT RED (5440 2925);
FORCEPROP 1 LAST VALUE 4.7K
J 0
(5445 3075);
DISPLAY 0.638298 (5445 3075);
FORCEPROP 1 LAST PART_NUMBER CS24702FB06
J 0
(5440 2875);
DISPLAY 0.638298 (5440 2875);
DISPLAY INVISIBLE (5440 2875);
FORCEPROP 1 LAST PATH I15
J 0
(5450 3175);
DISPLAY 0.978723 (5450 3175);
PAINT WHITE (5450 3175);
DISPLAY INVISIBLE (5450 3175);
FORCEPROP 2 LAST CDS_LIB pure_quanta
J 0
(5400 3000);
PAINT MONO (5400 3000);
DISPLAY INVISIBLE (5400 3000);
FORCEADD OFFPAGE..5
(5275 3275);
FORCEPROP 2 LAST $XR0 82 
J 0
(5051 3275);
DISPLAY 0.638298 (5051 3275);
PAINT MONO (5051 3275);
FORCEPROP 2 LAST $XR1 144 
J 0
(4931 3275);
DISPLAY 0.638298 (4931 3275);
PAINT MONO (4931 3275);
FORCEPROP 2 LAST PATH I16
J 0
(5000 3325);
DISPLAY 0.680851 (5000 3325);
DISPLAY INVISIBLE (5000 3325);
FORCEPROP 1 LAST COMMENT_BODY TRUE
J 0
(5375 3200);
DISPLAY 0.872340 (5375 3200);
PAINT GREEN (5375 3200);
DISPLAY INVISIBLE (5375 3200);
FORCEPROP 1 LAST OFFPAGE TRUE
J 0
(5600 3150);
DISPLAY 0.872340 (5600 3150);
DISPLAY INVISIBLE (5600 3150);
FORCEPROP 2 LAST CDS_LIB standard
J 0
(5275 3275);
PAINT MONO (5275 3275);
DISPLAY INVISIBLE (5275 3275);
FORCEADD OFFPAGE..5
(6125 3225);
FORCEPROP 2 LAST $XR0 155 
J 0
(5870 3225);
DISPLAY 0.638298 (5870 3225);
PAINT MONO (5870 3225);
FORCEPROP 2 LAST PATH I17
J 0
(5875 3275);
DISPLAY 0.680851 (5875 3275);
DISPLAY INVISIBLE (5875 3275);
FORCEPROP 1 LAST COMMENT_BODY TRUE
J 0
(6225 3150);
DISPLAY 0.872340 (6225 3150);
PAINT GREEN (6225 3150);
DISPLAY INVISIBLE (6225 3150);
FORCEPROP 1 LAST OFFPAGE TRUE
J 0
(6450 3100);
DISPLAY 0.872340 (6450 3100);
DISPLAY INVISIBLE (6450 3100);
FORCEPROP 2 LAST CDS_LIB standard
J 0
(6125 3225);
DISPLAY INVISIBLE (6125 3225);
FORCEADD OFFPAGE..1
(6250 1150);
FORCEPROP 2 LAST $XR0 144 
J 0
(5968 1150);
DISPLAY 0.638298 (5968 1150);
PAINT MONO (5968 1150);
FORCEPROP 2 LAST PATH I18
J 0
(6000 1200);
DISPLAY 0.680851 (6000 1200);
DISPLAY INVISIBLE (6000 1200);
FORCEPROP 1 LAST COMMENT_BODY TRUE
J 0
(6375 1050);
DISPLAY 0.872340 (6375 1050);
PAINT GREEN (6375 1050);
DISPLAY INVISIBLE (6375 1050);
FORCEPROP 1 LAST OFFPAGE TRUE
J 0
(6575 1025);
DISPLAY 0.872340 (6575 1025);
PAINT AQUA (6575 1025);
DISPLAY INVISIBLE (6575 1025);
FORCEPROP 2 LAST CDS_LIB standard
J 0
(6250 1150);
PAINT MONO (6250 1150);
DISPLAY INVISIBLE (6250 1150);
FORCEADD Q_RES..1
(7025 1150);
FORCEPROP 1 LAST LOCATION R3294
J 0
(6975 1200);
DISPLAY 0.978723 (6975 1200);
FORCEPROP 0 LAST $SEC 1
J 0
(6975 1250);
DISPLAY 0.680851 (6975 1250);
PAINT MONO (6975 1250);
DISPLAY INVISIBLE (6975 1250);
FORCEPROP 0 LAST CDS_SEC 1
J 0
(6975 1250);
DISPLAY 1.021277 (6975 1250);
DISPLAY INVISIBLE (6975 1250);
FORCEPROP 1 LASTPIN (6925 1150) $PN 1
J 0
(6937 1162);
DISPLAY 0.787234 (6937 1162);
PAINT MONO (6937 1162);
FORCEPROP 1 LASTPIN (7125 1150) $PN 2
J 0
(7087 1162);
DISPLAY 0.787234 (7087 1162);
PAINT MONO (7087 1162);
FORCEPROP 1 LAST VALUE 0
J 2
(7225 1150);
DISPLAY 0.638298 (7225 1150);
FORCEPROP 1 LAST MATERIAL CHIP
J 0
(7325 1150);
DISPLAY 0.638298 (7325 1150);
FORCEPROP 1 LAST TOLERANCE 5%
J 0
(7250 1150);
DISPLAY 0.638298 (7250 1150);
FORCEPROP 1 LAST PART_NUMBER CS00002JB13
J 0
(6900 1225);
DISPLAY 0.638298 (6900 1225);
DISPLAY INVISIBLE (6900 1225);
FORCEPROP 1 LAST PATH I19
J 0
(6975 1300);
DISPLAY 0.978723 (6975 1300);
PAINT WHITE (6975 1300);
DISPLAY INVISIBLE (6975 1300);
FORCEPROP 2 LAST CDS_LIB pure_quanta
J 0
(7025 1150);
DISPLAY INVISIBLE (7025 1150);
FORCEPROP 1 LAST WATTAGE 1/16W
J 2
(7200 1275);
DISPLAY 0.638298 (7200 1275);
DISPLAY INVISIBLE (7200 1275);
FORCEPROP 1 LAST PACK_TYPE 0402LF
J 0
(7300 1150);
DISPLAY 0.638298 (7300 1150);
DISPLAY INVISIBLE (7300 1150);
FORCEADD OFFPAGE..1
(6100 -525);
FORCEPROP 2 LAST $XR0 81 
J 0
(5879 -525);
DISPLAY 0.638298 (5879 -525);
PAINT MONO (5879 -525);
FORCEPROP 2 LAST $XR1 83 
J 0
(5789 -525);
DISPLAY 0.638298 (5789 -525);
PAINT MONO (5789 -525);
FORCEPROP 2 LAST PATH I2
J 0
(5825 -475);
DISPLAY 0.680851 (5825 -475);
DISPLAY INVISIBLE (5825 -475);
FORCEPROP 1 LAST COMMENT_BODY TRUE
J 0
(6225 -625);
DISPLAY 0.872340 (6225 -625);
PAINT GREEN (6225 -625);
DISPLAY INVISIBLE (6225 -625);
FORCEPROP 1 LAST OFFPAGE TRUE
J 0
(6425 -650);
DISPLAY 0.872340 (6425 -650);
PAINT AQUA (6425 -650);
DISPLAY INVISIBLE (6425 -650);
FORCEPROP 2 LAST CDS_LIB standard
J 0
(6100 -525);
DISPLAY INVISIBLE (6100 -525);
FORCEADD OFFPAGE..1
(7675 1050);
FORCEPROP 2 LAST $XR0 144 
J 0
(7423 1050);
DISPLAY 0.638298 (7423 1050);
PAINT MONO (7423 1050);
FORCEPROP 2 LAST PATH I20
J 0
(7400 1100);
DISPLAY 0.680851 (7400 1100);
DISPLAY INVISIBLE (7400 1100);
FORCEPROP 1 LAST COMMENT_BODY TRUE
J 0
(7800 950);
DISPLAY 0.872340 (7800 950);
PAINT GREEN (7800 950);
DISPLAY INVISIBLE (7800 950);
FORCEPROP 1 LAST OFFPAGE TRUE
J 0
(8000 925);
DISPLAY 0.872340 (8000 925);
PAINT AQUA (8000 925);
DISPLAY INVISIBLE (8000 925);
FORCEPROP 2 LAST CDS_LIB standard
J 0
(7675 1050);
DISPLAY INVISIBLE (7675 1050);
FORCEADD Q_RES..2
(7600 1450);
FORCEPROP 1 LAST LOCATION R3295
J 0
(7645 1575);
DISPLAY 0.978723 (7645 1575);
FORCEPROP 0 LAST $SEC 1
J 0
(7650 1625);
DISPLAY 0.680851 (7650 1625);
PAINT MONO (7650 1625);
DISPLAY INVISIBLE (7650 1625);
FORCEPROP 0 LAST CDS_SEC 1
J 0
(7650 1625);
DISPLAY 1.021277 (7650 1625);
DISPLAY INVISIBLE (7650 1625);
FORCEPROP 1 LASTPIN (7600 1550) $PN 1
J 0
(7605 1512);
DISPLAY 0.787234 (7605 1512);
PAINT MONO (7605 1512);
FORCEPROP 1 LASTPIN (7600 1350) $PN 2
J 0
(7605 1360);
DISPLAY 0.787234 (7605 1360);
PAINT MONO (7605 1360);
FORCEPROP 1 LAST VALUE 4.7K
J 0
(7645 1525);
DISPLAY 0.787234 (7645 1525);
FORCEPROP 1 LAST TOLERANCE 1%
J 0
(7645 1475);
DISPLAY 0.787234 (7645 1475);
FORCEPROP 1 LAST PACK_TYPE 0402LF
J 0
(7640 1275);
DISPLAY 0.787234 (7640 1275);
FORCEPROP 1 LAST WATTAGE 1/16W
J 0
(7640 1425);
DISPLAY 0.787234 (7640 1425);
FORCEPROP 1 LAST MATERIAL CHIP
J 0
(7640 1375);
DISPLAY 0.787234 (7640 1375);
FORCEPROP 1 LAST PART_NUMBER CS24702FB06
J 0
(7640 1325);
DISPLAY 0.787234 (7640 1325);
DISPLAY INVISIBLE (7640 1325);
FORCEPROP 1 LAST PATH I21
J 0
(7650 1625);
DISPLAY 0.978723 (7650 1625);
PAINT WHITE (7650 1625);
DISPLAY INVISIBLE (7650 1625);
FORCEPROP 2 LAST CDS_LIB pure_quanta
J 0
(7600 1450);
DISPLAY INVISIBLE (7600 1450);
FORCEADD UNIVERSAL_POWER..1
(7600 1700);
FORCEPROP 3 LASTPIN (7600 1650) SIG_NAME P3V3_M2_0\g
J 0
(7610 1660);
DISPLAY 0.659574 (7610 1660);
PAINT MONO (7610 1660);
DISPLAY INVISIBLE (7610 1660);
FORCEPROP 1 LAST HDL_POWER P3V3_M2_0
J 1
(7600 1750);
DISPLAY 0.872340 (7600 1750);
PAINT GREEN (7600 1750);
FORCEPROP 1 LAST PATH I22
J 0
(7650 1725);
DISPLAY 0.872340 (7650 1725);
PAINT AQUA (7650 1725);
DISPLAY INVISIBLE (7650 1725);
FORCEPROP 2 LAST CDS_LIB pure_quanta_power
J 0
(7600 1700);
DISPLAY INVISIBLE (7600 1700);
FORCEADD OFFPAGE..5
(6825 2325);
FORCEPROP 2 LAST $XR0 80 
J 0
(6601 2325);
DISPLAY 0.638298 (6601 2325);
PAINT MONO (6601 2325);
FORCEPROP 2 LAST PATH I23
J 0
(6550 2375);
DISPLAY 0.680851 (6550 2375);
DISPLAY INVISIBLE (6550 2375);
FORCEPROP 1 LAST COMMENT_BODY TRUE
J 0
(6925 2250);
DISPLAY 0.872340 (6925 2250);
PAINT GREEN (6925 2250);
DISPLAY INVISIBLE (6925 2250);
FORCEPROP 1 LAST OFFPAGE TRUE
J 0
(7150 2200);
DISPLAY 0.872340 (7150 2200);
DISPLAY INVISIBLE (7150 2200);
FORCEPROP 2 LAST CDS_LIB standard
J 0
(6825 2325);
PAINT MONO (6825 2325);
DISPLAY INVISIBLE (6825 2325);
FORCEADD Q_RES..2
(6925 2625);
FORCEPROP 1 LAST LOCATION R178
J 0
(6970 2750);
DISPLAY 0.787234 (6970 2750);
FORCEPROP 2 LAST $SEC 1
J 0
(6975 2850);
DISPLAY 0.680851 (6975 2850);
PAINT MONO (6975 2850);
DISPLAY INVISIBLE (6975 2850);
FORCEPROP 2 LAST CDS_SEC 1
J 0
(6975 2850);
DISPLAY 1.021277 (6975 2850);
DISPLAY INVISIBLE (6975 2850);
FORCEPROP 1 LASTPIN (6925 2725) $PN 1
J 0
(6930 2687);
DISPLAY 0.787234 (6930 2687);
FORCEPROP 1 LASTPIN (6925 2525) $PN 2
J 0
(6930 2535);
DISPLAY 0.787234 (6930 2535);
FORCEPROP 1 LAST VALUE 1K
J 0
(6970 2700);
DISPLAY 0.638298 (6970 2700);
FORCEPROP 1 LAST PACK_TYPE 0402LF
J 0
(6965 2450);
DISPLAY 0.638298 (6965 2450);
FORCEPROP 1 LAST TOLERANCE 1%
J 0
(6970 2650);
DISPLAY 0.787234 (6970 2650);
FORCEPROP 1 LAST WATTAGE 1/16W
J 0
(6965 2600);
DISPLAY 0.638298 (6965 2600);
FORCEPROP 1 LAST MATERIAL CHIP
J 0
(6965 2550);
DISPLAY 0.638298 (6965 2550);
FORCEPROP 1 LAST PART_NUMBER CS21002FB06
J 0
(6965 2500);
DISPLAY 0.638298 (6965 2500);
DISPLAY INVISIBLE (6965 2500);
FORCEPROP 1 LAST PATH I24
J 0
(6975 2800);
DISPLAY 0.978723 (6975 2800);
PAINT WHITE (6975 2800);
DISPLAY INVISIBLE (6975 2800);
FORCEPROP 2 LAST CDS_LIB pure_quanta
J 0
(6925 2625);
PAINT MONO (6925 2625);
DISPLAY INVISIBLE (6925 2625);
FORCEADD UNIVERSAL_POWER..1
(6925 2850);
FORCEPROP 3 LASTPIN (6925 2800) SIG_NAME P3V3_AUX\g
J 0
(6935 2810);
DISPLAY 0.659574 (6935 2810);
PAINT MONO (6935 2810);
DISPLAY INVISIBLE (6935 2810);
FORCEPROP 1 LAST HDL_POWER P3V3_AUX
J 1
(6925 2900);
DISPLAY 0.872340 (6925 2900);
PAINT GREEN (6925 2900);
FORCEPROP 1 LAST PATH I25
J 0
(6975 2875);
DISPLAY 0.872340 (6975 2875);
PAINT AQUA (6975 2875);
DISPLAY INVISIBLE (6975 2875);
FORCEPROP 2 LAST CDS_LIB pure_quanta_power
J 0
(6925 2850);
PAINT MONO (6925 2850);
DISPLAY INVISIBLE (6925 2850);
FORCEADD OFFPAGE..1
(6425 3375);
FORCEPROP 2 LAST $XR0 144 
J 0
(6173 3375);
DISPLAY 0.638298 (6173 3375);
PAINT MONO (6173 3375);
FORCEPROP 2 LAST PATH I26
J 0
(6150 3425);
DISPLAY 0.680851 (6150 3425);
DISPLAY INVISIBLE (6150 3425);
FORCEPROP 1 LAST COMMENT_BODY TRUE
J 0
(6550 3275);
DISPLAY 0.872340 (6550 3275);
PAINT GREEN (6550 3275);
DISPLAY INVISIBLE (6550 3275);
FORCEPROP 1 LAST OFFPAGE TRUE
J 0
(6750 3250);
DISPLAY 0.872340 (6750 3250);
DISPLAY INVISIBLE (6750 3250);
FORCEPROP 2 LAST CDS_LIB standard
J 0
(6425 3375);
PAINT MONO (6425 3375);
DISPLAY INVISIBLE (6425 3375);
FORCEADD Q_RES..1
(6375 3275);
FORCEPROP 1 LAST LOCATION R153
J 0
(6150 3275);
DISPLAY 0.787234 (6150 3275);
FORCEPROP 2 LAST $SEC 1
J 0
(6325 3475);
DISPLAY 0.680851 (6325 3475);
PAINT MONO (6325 3475);
DISPLAY INVISIBLE (6325 3475);
FORCEPROP 2 LAST CDS_SEC 1
J 0
(6325 3475);
DISPLAY 1.021277 (6325 3475);
DISPLAY INVISIBLE (6325 3475);
FORCEPROP 1 LASTPIN (6275 3275) $PN 1
J 0
(6287 3287);
DISPLAY 0.787234 (6287 3287);
FORCEPROP 1 LASTPIN (6475 3275) $PN 2
J 0
(6437 3287);
DISPLAY 0.787234 (6437 3287);
FORCEPROP 1 LAST TOLERANCE 5%
J 0
(6575 3275);
DISPLAY 0.638298 (6575 3275);
FORCEPROP 1 LAST MATERIAL CHIP
J 0
(6650 3275);
DISPLAY 0.638298 (6650 3275);
FORCEPROP 1 LAST VALUE 0
J 2
(6550 3275);
DISPLAY 0.638298 (6550 3275);
FORCEPROP 1 LAST PART_NUMBER CS00002JB13
J 0
(6250 3350);
DISPLAY 0.638298 (6250 3350);
DISPLAY INVISIBLE (6250 3350);
FORCEPROP 1 LAST PATH I27
J 0
(6325 3425);
DISPLAY 0.978723 (6325 3425);
PAINT WHITE (6325 3425);
DISPLAY INVISIBLE (6325 3425);
FORCEPROP 2 LAST CDS_LIB pure_quanta
J 0
(6375 3275);
PAINT MONO (6375 3275);
DISPLAY INVISIBLE (6375 3275);
FORCEPROP 1 LAST WATTAGE 1/16W
J 2
(6550 3400);
DISPLAY 0.638298 (6550 3400);
DISPLAY INVISIBLE (6550 3400);
FORCEPROP 1 LAST PACK_TYPE 0402LF
J 0
(6650 3275);
DISPLAY 0.638298 (6650 3275);
DISPLAY INVISIBLE (6650 3275);
FORCEADD OFFPAGE..1
(6825 3075);
FORCEPROP 2 LAST $XR0 55 
J 0
(6574 3075);
DISPLAY 0.638298 (6574 3075);
PAINT MONO (6574 3075);
FORCEPROP 2 LAST PATH I28
J 0
(6575 3125);
DISPLAY 0.680851 (6575 3125);
DISPLAY INVISIBLE (6575 3125);
FORCEPROP 1 LAST COMMENT_BODY TRUE
J 0
(6950 2975);
DISPLAY 0.872340 (6950 2975);
PAINT GREEN (6950 2975);
DISPLAY INVISIBLE (6950 2975);
FORCEPROP 1 LAST OFFPAGE TRUE
J 0
(7150 2950);
DISPLAY 0.872340 (7150 2950);
DISPLAY INVISIBLE (7150 2950);
FORCEPROP 2 LAST CDS_LIB standard
J 0
(6825 3075);
PAINT MONO (6825 3075);
DISPLAY INVISIBLE (6825 3075);
FORCEADD OFFPAGE..1
(6825 3125);
FORCEPROP 2 LAST $XR0 55 
J 0
(6574 3125);
DISPLAY 0.638298 (6574 3125);
PAINT MONO (6574 3125);
FORCEPROP 2 LAST PATH I29
J 0
(6575 3175);
DISPLAY 0.680851 (6575 3175);
DISPLAY INVISIBLE (6575 3175);
FORCEPROP 1 LAST COMMENT_BODY TRUE
J 0
(6950 3025);
DISPLAY 0.872340 (6950 3025);
PAINT GREEN (6950 3025);
DISPLAY INVISIBLE (6950 3025);
FORCEPROP 1 LAST OFFPAGE TRUE
J 0
(7150 3000);
DISPLAY 0.872340 (7150 3000);
DISPLAY INVISIBLE (7150 3000);
FORCEPROP 2 LAST CDS_LIB standard
J 0
(6825 3125);
PAINT MONO (6825 3125);
DISPLAY INVISIBLE (6825 3125);
FORCEADD UNIVERSAL_GND..1
(8000 -1125);
FORCEPROP 3 LASTPIN (8000 -1075) SIG_NAME GND\g
J 0
(8010 -1065);
DISPLAY 0.659574 (8010 -1065);
PAINT MONO (8010 -1065);
DISPLAY INVISIBLE (8010 -1065);
FORCEPROP 1 LAST PATH I3
J 0
(8075 -1125);
DISPLAY 0.872340 (8075 -1125);
PAINT AQUA (8075 -1125);
DISPLAY INVISIBLE (8075 -1125);
FORCEPROP 1 LAST HDL_POWER GND
J 1
(8025 -1200);
DISPLAY 0.872340 (8025 -1200);
PAINT GREEN (8025 -1200);
DISPLAY INVISIBLE (8025 -1200);
FORCEPROP 2 LAST CDS_LIB pure_quanta_power
J 0
(8000 -1125);
DISPLAY INVISIBLE (8000 -1125);
FORCEADD Q_RES..1
(6925 3225);
FORCEPROP 1 LAST LOCATION R3301
J 0
(6750 3225);
DISPLAY 0.510638 (6750 3225);
FORCEPROP 0 LAST $SEC 1
J 0
(7225 3250);
DISPLAY 0.680851 (7225 3250);
PAINT MONO (7225 3250);
DISPLAY INVISIBLE (7225 3250);
FORCEPROP 0 LAST CDS_SEC 1
J 0
(7225 3250);
DISPLAY 1.021277 (7225 3250);
DISPLAY INVISIBLE (7225 3250);
FORCEPROP 1 LASTPIN (6825 3225) $PN 1
J 0
(6837 3237);
DISPLAY 0.787234 (6837 3237);
PAINT MONO (6837 3237);
FORCEPROP 1 LASTPIN (7025 3225) $PN 2
J 0
(6987 3237);
DISPLAY 0.787234 (6987 3237);
PAINT MONO (6987 3237);
FORCEPROP 1 LAST MATERIAL CHIP
J 0
(7225 3225);
DISPLAY 0.510638 (7225 3225);
FORCEPROP 1 LAST TOLERANCE 1%
J 0
(7150 3225);
DISPLAY 0.510638 (7150 3225);
FORCEPROP 1 LAST VALUE 33.2
J 2
(7125 3225);
DISPLAY 0.510638 (7125 3225);
FORCEPROP 1 LAST PART_NUMBER CS03322FB03
J 0
(6800 3175);
DISPLAY 0.510638 (6800 3175);
DISPLAY INVISIBLE (6800 3175);
FORCEPROP 1 LAST PATH I30
J 0
(6875 3375);
DISPLAY 0.978723 (6875 3375);
PAINT WHITE (6875 3375);
DISPLAY INVISIBLE (6875 3375);
FORCEPROP 2 LAST CDS_LIB pure_quanta
J 0
(6925 3225);
DISPLAY INVISIBLE (6925 3225);
FORCEPROP 1 LAST PACK_TYPE 0402LF
J 0
(6800 3350);
DISPLAY 0.510638 (6800 3350);
DISPLAY INVISIBLE (6800 3350);
FORCEPROP 1 LAST WATTAGE 1/16W
J 2
(7100 3350);
DISPLAY 0.510638 (7100 3350);
DISPLAY INVISIBLE (7100 3350);
FORCEADD OFFPAGE..1
(6825 3475);
FORCEPROP 2 LAST $XR0 144 
J 0
(6543 3475);
DISPLAY 0.638298 (6543 3475);
PAINT MONO (6543 3475);
FORCEPROP 2 LAST PATH I31
J 0
(6575 3525);
DISPLAY 0.680851 (6575 3525);
DISPLAY INVISIBLE (6575 3525);
FORCEPROP 1 LAST COMMENT_BODY TRUE
J 0
(6950 3375);
DISPLAY 0.872340 (6950 3375);
PAINT GREEN (6950 3375);
DISPLAY INVISIBLE (6950 3375);
FORCEPROP 1 LAST OFFPAGE TRUE
J 0
(7150 3350);
DISPLAY 0.872340 (7150 3350);
DISPLAY INVISIBLE (7150 3350);
FORCEPROP 2 LAST CDS_LIB standard
J 0
(6825 3475);
PAINT MONO (6825 3475);
DISPLAY INVISIBLE (6825 3475);
FORCEADD Q_RES..2
R 2
(6925 3850);
FORCEPROP 1 LAST LOCATION R155
J 2
(6880 3975);
DISPLAY 0.638298 (6880 3975);
FORCEPROP 2 LAST $SEC 1
J 2
(6875 4075);
DISPLAY 0.680851 (6875 4075);
PAINT MONO (6875 4075);
DISPLAY INVISIBLE (6875 4075);
FORCEPROP 2 LAST CDS_SEC 1
J 2
(6875 4075);
DISPLAY 1.021277 (6875 4075);
DISPLAY INVISIBLE (6875 4075);
FORCEPROP 1 LASTPIN (6925 3950) $PN 1
J 2
(6920 3912);
DISPLAY 0.787234 (6920 3912);
FORCEPROP 1 LASTPIN (6925 3750) $PN 2
J 2
(6920 3760);
DISPLAY 0.787234 (6920 3760);
FORCEPROP 1 LAST MATERIAL EMPTY
J 2
(6885 3775);
DISPLAY 0.510638 (6885 3775);
PAINT RED (6885 3775);
FORCEPROP 1 LAST VALUE 1K
J 2
(6880 3925);
DISPLAY 0.510638 (6880 3925);
FORCEPROP 1 LAST WATTAGE 1/16W
J 2
(6885 3825);
DISPLAY 0.510638 (6885 3825);
FORCEPROP 1 LAST TOLERANCE 1%
J 2
(6880 3875);
DISPLAY 0.510638 (6880 3875);
FORCEPROP 1 LAST PACK_TYPE 0402LF
J 2
(6885 3675);
DISPLAY 0.510638 (6885 3675);
FORCEPROP 1 LAST PART_NUMBER CS21002FB06
J 2
(6885 3725);
DISPLAY 0.510638 (6885 3725);
DISPLAY INVISIBLE (6885 3725);
FORCEPROP 1 LAST PATH I32
J 2
(6875 4025);
DISPLAY 0.978723 (6875 4025);
PAINT WHITE (6875 4025);
DISPLAY INVISIBLE (6875 4025);
FORCEPROP 2 LAST CDS_LIB pure_quanta
J 2
(6925 3850);
PAINT MONO (6925 3850);
DISPLAY INVISIBLE (6925 3850);
FORCEADD UNIVERSAL_GND..1
(7925 2025);
FORCEPROP 3 LASTPIN (7925 2075) SIG_NAME GND\g
J 0
(7935 2085);
DISPLAY 0.659574 (7935 2085);
PAINT MONO (7935 2085);
DISPLAY INVISIBLE (7935 2085);
FORCEPROP 1 LAST PATH I33
J 0
(8000 2025);
DISPLAY 0.872340 (8000 2025);
PAINT AQUA (8000 2025);
DISPLAY INVISIBLE (8000 2025);
FORCEPROP 1 LAST HDL_POWER GND
J 1
(7950 1950);
DISPLAY 0.872340 (7950 1950);
PAINT GREEN (7950 1950);
DISPLAY INVISIBLE (7950 1950);
FORCEPROP 2 LAST CDS_LIB pure_quanta_power
J 0
(7925 2025);
PAINT MONO (7925 2025);
DISPLAY INVISIBLE (7925 2025);
FORCEADD TAP..1
R 2
(7200 3775);
FORCEPROP 3 LASTPIN (7250 3775) SIG_NAME P3E_CPU1_P4_RX_DN<1>
J 0
(7260 3785);
DISPLAY 0.659574 (7260 3785);
PAINT MONO (7260 3785);
DISPLAY INVISIBLE (7260 3785);
FORCEPROP 1 LASTPIN (7250 3775) BN 1
J 2
(7262 3783);
DISPLAY 0.680851 (7262 3783);
PAINT GREEN (7262 3783);
FORCEPROP 1 LAST PATH I34
J 2
(7202 3775);
DISPLAY 0.872340 (7202 3775);
PAINT GREEN (7202 3775);
DISPLAY INVISIBLE (7202 3775);
FORCEPROP 1 LAST HDL_TAP TRUE
J 2
(6875 3650);
DISPLAY 0.872340 (6875 3650);
PAINT GREEN (6875 3650);
DISPLAY INVISIBLE (6875 3650);
FORCEPROP 1 LAST BODY_TYPE PLUMBING
J 2
(7200 3825);
DISPLAY 0.872340 (7200 3825);
PAINT GREEN (7200 3825);
DISPLAY INVISIBLE (7200 3825);
FORCEPROP 2 LAST CDS_LIB standard
J 0
(7200 3775);
DISPLAY INVISIBLE (7200 3775);
FORCEADD TAP..1
R 2
(7350 3825);
FORCEPROP 3 LASTPIN (7400 3825) SIG_NAME P3E_CPU1_P4_RX_DP<1>
J 0
(7410 3835);
DISPLAY 0.659574 (7410 3835);
PAINT MONO (7410 3835);
DISPLAY INVISIBLE (7410 3835);
FORCEPROP 1 LASTPIN (7400 3825) BN 1
J 2
(7412 3833);
DISPLAY 0.680851 (7412 3833);
PAINT GREEN (7412 3833);
FORCEPROP 1 LAST PATH I35
J 2
(7352 3825);
DISPLAY 0.872340 (7352 3825);
PAINT GREEN (7352 3825);
DISPLAY INVISIBLE (7352 3825);
FORCEPROP 1 LAST HDL_TAP TRUE
J 2
(7025 3700);
DISPLAY 0.872340 (7025 3700);
PAINT GREEN (7025 3700);
DISPLAY INVISIBLE (7025 3700);
FORCEPROP 1 LAST BODY_TYPE PLUMBING
J 2
(7350 3875);
DISPLAY 0.872340 (7350 3875);
PAINT GREEN (7350 3875);
DISPLAY INVISIBLE (7350 3875);
FORCEPROP 2 LAST CDS_LIB standard
J 0
(7350 3825);
DISPLAY INVISIBLE (7350 3825);
FORCEADD TAP..1
R 2
(7675 3675);
FORCEPROP 3 LASTPIN (7725 3675) SIG_NAME P3E_CPU1_P4_TX_C_DN<1>
J 0
(7735 3685);
DISPLAY 0.659574 (7735 3685);
PAINT MONO (7735 3685);
DISPLAY INVISIBLE (7735 3685);
FORCEPROP 1 LASTPIN (7725 3675) BN 1
J 2
(7737 3683);
DISPLAY 0.680851 (7737 3683);
PAINT GREEN (7737 3683);
FORCEPROP 1 LAST PATH I36
J 2
(7677 3675);
DISPLAY 0.872340 (7677 3675);
PAINT GREEN (7677 3675);
DISPLAY INVISIBLE (7677 3675);
FORCEPROP 1 LAST HDL_TAP TRUE
J 2
(7350 3550);
DISPLAY 0.872340 (7350 3550);
PAINT GREEN (7350 3550);
DISPLAY INVISIBLE (7350 3550);
FORCEPROP 1 LAST BODY_TYPE PLUMBING
J 2
(7675 3725);
DISPLAY 0.872340 (7675 3725);
PAINT GREEN (7675 3725);
DISPLAY INVISIBLE (7675 3725);
FORCEPROP 2 LAST CDS_LIB standard
J 0
(7675 3675);
DISPLAY INVISIBLE (7675 3675);
FORCEADD TAP..1
R 2
(7525 3725);
FORCEPROP 3 LASTPIN (7575 3725) SIG_NAME P3E_CPU1_P4_TX_C_DP<1>
J 0
(7585 3735);
DISPLAY 0.659574 (7585 3735);
PAINT MONO (7585 3735);
DISPLAY INVISIBLE (7585 3735);
FORCEPROP 1 LASTPIN (7575 3725) BN 1
J 2
(7587 3733);
DISPLAY 0.680851 (7587 3733);
PAINT GREEN (7587 3733);
FORCEPROP 1 LAST PATH I37
J 2
(7527 3725);
DISPLAY 0.872340 (7527 3725);
PAINT GREEN (7527 3725);
DISPLAY INVISIBLE (7527 3725);
FORCEPROP 1 LAST HDL_TAP TRUE
J 2
(7200 3600);
DISPLAY 0.872340 (7200 3600);
PAINT GREEN (7200 3600);
DISPLAY INVISIBLE (7200 3600);
FORCEPROP 1 LAST BODY_TYPE PLUMBING
J 2
(7525 3775);
DISPLAY 0.872340 (7525 3775);
PAINT GREEN (7525 3775);
DISPLAY INVISIBLE (7525 3775);
FORCEPROP 2 LAST CDS_LIB standard
J 0
(7525 3725);
DISPLAY INVISIBLE (7525 3725);
FORCEADD TAP..1
R 2
(7525 3975);
FORCEPROP 3 LASTPIN (7575 3975) SIG_NAME P3E_CPU1_P4_TX_C_DP<2>
J 0
(7585 3985);
DISPLAY 0.659574 (7585 3985);
PAINT MONO (7585 3985);
DISPLAY INVISIBLE (7585 3985);
FORCEPROP 1 LASTPIN (7575 3975) BN 2
J 2
(7587 3983);
DISPLAY 0.680851 (7587 3983);
PAINT GREEN (7587 3983);
FORCEPROP 1 LAST PATH I38
J 2
(7527 3975);
DISPLAY 0.872340 (7527 3975);
PAINT GREEN (7527 3975);
DISPLAY INVISIBLE (7527 3975);
FORCEPROP 1 LAST HDL_TAP TRUE
J 2
(7200 3850);
DISPLAY 0.872340 (7200 3850);
PAINT GREEN (7200 3850);
DISPLAY INVISIBLE (7200 3850);
FORCEPROP 1 LAST BODY_TYPE PLUMBING
J 2
(7525 4025);
DISPLAY 0.872340 (7525 4025);
PAINT GREEN (7525 4025);
DISPLAY INVISIBLE (7525 4025);
FORCEPROP 2 LAST CDS_LIB standard
J 0
(7525 3975);
DISPLAY INVISIBLE (7525 3975);
FORCEADD TAP..1
R 2
(7675 3925);
FORCEPROP 3 LASTPIN (7725 3925) SIG_NAME P3E_CPU1_P4_TX_C_DN<2>
J 0
(7735 3935);
DISPLAY 0.659574 (7735 3935);
PAINT MONO (7735 3935);
DISPLAY INVISIBLE (7735 3935);
FORCEPROP 1 LASTPIN (7725 3925) BN 2
J 2
(7737 3933);
DISPLAY 0.680851 (7737 3933);
PAINT GREEN (7737 3933);
FORCEPROP 1 LAST PATH I39
J 2
(7677 3925);
DISPLAY 0.872340 (7677 3925);
PAINT GREEN (7677 3925);
DISPLAY INVISIBLE (7677 3925);
FORCEPROP 1 LAST HDL_TAP TRUE
J 2
(7350 3800);
DISPLAY 0.872340 (7350 3800);
PAINT GREEN (7350 3800);
DISPLAY INVISIBLE (7350 3800);
FORCEPROP 1 LAST BODY_TYPE PLUMBING
J 2
(7675 3975);
DISPLAY 0.872340 (7675 3975);
PAINT GREEN (7675 3975);
DISPLAY INVISIBLE (7675 3975);
FORCEPROP 2 LAST CDS_LIB standard
J 0
(7675 3925);
DISPLAY INVISIBLE (7675 3925);
FORCEADD UNIVERSAL_GND..1
(7200 -675);
FORCEPROP 3 LASTPIN (7200 -625) SIG_NAME GND\g
J 0
(7210 -615);
DISPLAY 0.659574 (7210 -615);
PAINT MONO (7210 -615);
DISPLAY INVISIBLE (7210 -615);
FORCEPROP 1 LAST PATH I4
J 0
(7275 -675);
DISPLAY 0.872340 (7275 -675);
PAINT AQUA (7275 -675);
DISPLAY INVISIBLE (7275 -675);
FORCEPROP 1 LAST HDL_POWER GND
J 1
(7225 -750);
DISPLAY 0.872340 (7225 -750);
PAINT GREEN (7225 -750);
DISPLAY INVISIBLE (7225 -750);
FORCEPROP 2 LAST CDS_LIB pure_quanta_power
J 0
(7200 -675);
DISPLAY INVISIBLE (7200 -675);
FORCEADD OFFPAGE..5
(6075 4450);
FORCEPROP 2 LAST $XR0 53 
J 0
(5851 4450);
DISPLAY 0.638298 (5851 4450);
PAINT MONO (5851 4450);
FORCEPROP 2 LAST PATH I40
J 0
(5825 4500);
DISPLAY 0.680851 (5825 4500);
DISPLAY INVISIBLE (5825 4500);
FORCEPROP 1 LAST COMMENT_BODY TRUE
J 0
(6175 4375);
DISPLAY 0.872340 (6175 4375);
PAINT GREEN (6175 4375);
DISPLAY INVISIBLE (6175 4375);
FORCEPROP 1 LAST OFFPAGE TRUE
J 0
(6400 4325);
DISPLAY 0.872340 (6400 4325);
DISPLAY INVISIBLE (6400 4325);
FORCEPROP 2 LAST CDS_LIB standard
J 0
(6075 4450);
PAINT MONO (6075 4450);
DISPLAY INVISIBLE (6075 4450);
FORCEADD OFFPAGE..5
(6075 4400);
FORCEPROP 2 LAST $XR0 53 
J 0
(5851 4400);
DISPLAY 0.638298 (5851 4400);
PAINT MONO (5851 4400);
FORCEPROP 2 LAST PATH I41
J 0
(5825 4450);
DISPLAY 0.680851 (5825 4450);
DISPLAY INVISIBLE (5825 4450);
FORCEPROP 1 LAST COMMENT_BODY TRUE
J 0
(6175 4325);
DISPLAY 0.872340 (6175 4325);
PAINT GREEN (6175 4325);
DISPLAY INVISIBLE (6175 4325);
FORCEPROP 1 LAST OFFPAGE TRUE
J 0
(6400 4275);
DISPLAY 0.872340 (6400 4275);
DISPLAY INVISIBLE (6400 4275);
FORCEPROP 2 LAST CDS_LIB standard
J 0
(6075 4400);
PAINT MONO (6075 4400);
DISPLAY INVISIBLE (6075 4400);
FORCEADD OFFPAGE..1
(6075 4500);
FORCEPROP 2 LAST $XR0 67 
J 0
(5854 4500);
DISPLAY 0.638298 (5854 4500);
PAINT MONO (5854 4500);
FORCEPROP 2 LAST PATH I42
J 0
(5800 4550);
DISPLAY 0.680851 (5800 4550);
DISPLAY INVISIBLE (5800 4550);
FORCEPROP 1 LAST COMMENT_BODY TRUE
J 0
(6200 4400);
DISPLAY 0.872340 (6200 4400);
PAINT GREEN (6200 4400);
DISPLAY INVISIBLE (6200 4400);
FORCEPROP 1 LAST OFFPAGE TRUE
J 0
(6400 4375);
DISPLAY 0.872340 (6400 4375);
PAINT GREEN (6400 4375);
DISPLAY INVISIBLE (6400 4375);
FORCEPROP 2 LAST CDS_LIB standard
J 0
(6075 4500);
PAINT MONO (6075 4500);
DISPLAY INVISIBLE (6075 4500);
FORCEADD OFFPAGE..1
(6075 4550);
FORCEPROP 2 LAST $XR0 67 
J 0
(5854 4550);
DISPLAY 0.638298 (5854 4550);
PAINT MONO (5854 4550);
FORCEPROP 2 LAST PATH I43
J 0
(5800 4600);
DISPLAY 0.680851 (5800 4600);
DISPLAY INVISIBLE (5800 4600);
FORCEPROP 1 LAST COMMENT_BODY TRUE
J 0
(6200 4450);
DISPLAY 0.872340 (6200 4450);
PAINT GREEN (6200 4450);
DISPLAY INVISIBLE (6200 4450);
FORCEPROP 1 LAST OFFPAGE TRUE
J 0
(6400 4425);
DISPLAY 0.872340 (6400 4425);
PAINT GREEN (6400 4425);
DISPLAY INVISIBLE (6400 4425);
FORCEPROP 2 LAST CDS_LIB standard
J 0
(6075 4550);
PAINT MONO (6075 4550);
DISPLAY INVISIBLE (6075 4550);
FORCEADD UNIVERSAL_POWER..1
(6925 4075);
FORCEPROP 3 LASTPIN (6925 4025) SIG_NAME P3V3_AUX\g
J 0
(6935 4035);
DISPLAY 0.659574 (6935 4035);
PAINT MONO (6935 4035);
DISPLAY INVISIBLE (6935 4035);
FORCEPROP 1 LAST HDL_POWER P3V3_AUX
J 1
(6925 4125);
DISPLAY 0.872340 (6925 4125);
PAINT GREEN (6925 4125);
FORCEPROP 1 LAST PATH I44
J 0
(6975 4100);
DISPLAY 0.872340 (6975 4100);
PAINT AQUA (6975 4100);
DISPLAY INVISIBLE (6975 4100);
FORCEPROP 2 LAST CDS_LIB pure_quanta_power
J 0
(6925 4075);
PAINT MONO (6925 4075);
DISPLAY INVISIBLE (6925 4075);
FORCEADD TAP..1
R 2
(7200 4025);
FORCEPROP 3 LASTPIN (7250 4025) SIG_NAME P3E_CPU1_P4_RX_DN<2>
J 0
(7260 4035);
DISPLAY 0.659574 (7260 4035);
PAINT MONO (7260 4035);
DISPLAY INVISIBLE (7260 4035);
FORCEPROP 1 LASTPIN (7250 4025) BN 2
J 2
(7262 4033);
DISPLAY 0.680851 (7262 4033);
PAINT GREEN (7262 4033);
FORCEPROP 1 LAST PATH I45
J 2
(7202 4025);
DISPLAY 0.872340 (7202 4025);
PAINT GREEN (7202 4025);
DISPLAY INVISIBLE (7202 4025);
FORCEPROP 1 LAST HDL_TAP TRUE
J 2
(6875 3900);
DISPLAY 0.872340 (6875 3900);
PAINT GREEN (6875 3900);
DISPLAY INVISIBLE (6875 3900);
FORCEPROP 1 LAST BODY_TYPE PLUMBING
J 2
(7200 4075);
DISPLAY 0.872340 (7200 4075);
PAINT GREEN (7200 4075);
DISPLAY INVISIBLE (7200 4075);
FORCEPROP 2 LAST CDS_LIB standard
J 0
(7200 4025);
DISPLAY INVISIBLE (7200 4025);
FORCEADD TAP..1
R 2
(7200 4275);
FORCEPROP 3 LASTPIN (7250 4275) SIG_NAME P3E_CPU1_P4_RX_DN<3>
J 0
(7260 4285);
DISPLAY 0.659574 (7260 4285);
PAINT MONO (7260 4285);
DISPLAY INVISIBLE (7260 4285);
FORCEPROP 1 LASTPIN (7250 4275) BN 3
J 2
(7262 4283);
DISPLAY 0.680851 (7262 4283);
PAINT GREEN (7262 4283);
FORCEPROP 1 LAST PATH I46
J 2
(7202 4275);
DISPLAY 0.872340 (7202 4275);
PAINT GREEN (7202 4275);
DISPLAY INVISIBLE (7202 4275);
FORCEPROP 1 LAST HDL_TAP TRUE
J 2
(6875 4150);
DISPLAY 0.872340 (6875 4150);
PAINT GREEN (6875 4150);
DISPLAY INVISIBLE (6875 4150);
FORCEPROP 1 LAST BODY_TYPE PLUMBING
J 2
(7200 4325);
DISPLAY 0.872340 (7200 4325);
PAINT GREEN (7200 4325);
DISPLAY INVISIBLE (7200 4325);
FORCEPROP 2 LAST CDS_LIB standard
J 0
(7200 4275);
DISPLAY INVISIBLE (7200 4275);
FORCEADD TAP..1
R 2
(7350 4075);
FORCEPROP 3 LASTPIN (7400 4075) SIG_NAME P3E_CPU1_P4_RX_DP<2>
J 0
(7410 4085);
DISPLAY 0.659574 (7410 4085);
PAINT MONO (7410 4085);
DISPLAY INVISIBLE (7410 4085);
FORCEPROP 1 LASTPIN (7400 4075) BN 2
J 2
(7412 4083);
DISPLAY 0.680851 (7412 4083);
PAINT GREEN (7412 4083);
FORCEPROP 1 LAST PATH I47
J 2
(7352 4075);
DISPLAY 0.872340 (7352 4075);
PAINT GREEN (7352 4075);
DISPLAY INVISIBLE (7352 4075);
FORCEPROP 1 LAST HDL_TAP TRUE
J 2
(7025 3950);
DISPLAY 0.872340 (7025 3950);
PAINT GREEN (7025 3950);
DISPLAY INVISIBLE (7025 3950);
FORCEPROP 1 LAST BODY_TYPE PLUMBING
J 2
(7350 4125);
DISPLAY 0.872340 (7350 4125);
PAINT GREEN (7350 4125);
DISPLAY INVISIBLE (7350 4125);
FORCEPROP 2 LAST CDS_LIB standard
J 0
(7350 4075);
DISPLAY INVISIBLE (7350 4075);
FORCEADD TAP..1
R 2
(7350 4325);
FORCEPROP 3 LASTPIN (7400 4325) SIG_NAME P3E_CPU1_P4_RX_DP<3>
J 0
(7410 4335);
DISPLAY 0.659574 (7410 4335);
PAINT MONO (7410 4335);
DISPLAY INVISIBLE (7410 4335);
FORCEPROP 1 LASTPIN (7400 4325) BN 3
J 2
(7412 4333);
DISPLAY 0.680851 (7412 4333);
PAINT GREEN (7412 4333);
FORCEPROP 1 LAST PATH I48
J 2
(7352 4325);
DISPLAY 0.872340 (7352 4325);
PAINT GREEN (7352 4325);
DISPLAY INVISIBLE (7352 4325);
FORCEPROP 1 LAST HDL_TAP TRUE
J 2
(7025 4200);
DISPLAY 0.872340 (7025 4200);
PAINT GREEN (7025 4200);
DISPLAY INVISIBLE (7025 4200);
FORCEPROP 1 LAST BODY_TYPE PLUMBING
J 2
(7350 4375);
DISPLAY 0.872340 (7350 4375);
PAINT GREEN (7350 4375);
DISPLAY INVISIBLE (7350 4375);
FORCEPROP 2 LAST CDS_LIB standard
J 0
(7350 4325);
DISPLAY INVISIBLE (7350 4325);
FORCEADD TAP..1
R 2
(7525 4225);
FORCEPROP 3 LASTPIN (7575 4225) SIG_NAME P3E_CPU1_P4_TX_C_DP<3>
J 0
(7585 4235);
DISPLAY 0.659574 (7585 4235);
PAINT MONO (7585 4235);
DISPLAY INVISIBLE (7585 4235);
FORCEPROP 1 LASTPIN (7575 4225) BN 3
J 2
(7587 4233);
DISPLAY 0.680851 (7587 4233);
PAINT GREEN (7587 4233);
FORCEPROP 1 LAST PATH I49
J 2
(7527 4225);
DISPLAY 0.872340 (7527 4225);
PAINT GREEN (7527 4225);
DISPLAY INVISIBLE (7527 4225);
FORCEPROP 1 LAST HDL_TAP TRUE
J 2
(7200 4100);
DISPLAY 0.872340 (7200 4100);
PAINT GREEN (7200 4100);
DISPLAY INVISIBLE (7200 4100);
FORCEPROP 1 LAST BODY_TYPE PLUMBING
J 2
(7525 4275);
DISPLAY 0.872340 (7525 4275);
PAINT GREEN (7525 4275);
DISPLAY INVISIBLE (7525 4275);
FORCEPROP 2 LAST CDS_LIB standard
J 0
(7525 4225);
DISPLAY INVISIBLE (7525 4225);
FORCEADD SN74LVC2G07DCKR..1
(7625 -475);
FORCEPROP 1 LAST LOCATION U259
J 0
(7450 -270);
DISPLAY 0.723404 (7450 -270);
PAINT GREEN (7450 -270);
FORCEPROP 0 LAST $SEC 1
J 0
(7450 -125);
DISPLAY 0.680851 (7450 -125);
PAINT MONO (7450 -125);
DISPLAY INVISIBLE (7450 -125);
FORCEPROP 0 LAST CDS_SEC 1
J 0
(7450 -125);
DISPLAY 1.021277 (7450 -125);
DISPLAY INVISIBLE (7450 -125);
FORCEPROP 0 LASTPIN (7300 -425) $PN 1
J 2
(7290 -415);
DISPLAY 0.680851 (7290 -415);
PAINT MONO (7290 -415);
FORCEPROP 0 LASTPIN (7950 -425) $PN 6
J 0
(7960 -415);
DISPLAY 0.680851 (7960 -415);
PAINT MONO (7960 -415);
FORCEPROP 0 LASTPIN (7300 -525) $PN 3
J 2
(7290 -515);
DISPLAY 0.680851 (7290 -515);
PAINT MONO (7290 -515);
FORCEPROP 0 LASTPIN (7950 -525) $PN 4
J 0
(7960 -515);
DISPLAY 0.680851 (7960 -515);
PAINT MONO (7960 -515);
FORCEPROP 0 LASTPIN (7300 -475) $PN 2
J 2
(7290 -465);
DISPLAY 0.680851 (7290 -465);
PAINT MONO (7290 -465);
FORCEPROP 0 LASTPIN (7950 -475) $PN 5
J 0
(7960 -465);
DISPLAY 0.680851 (7960 -465);
PAINT MONO (7960 -465);
FORCEPROP 2 LAST VALUE SN74LVC2G07DCKR
J 0
(7450 -175);
DISPLAY 1.021277 (7450 -175);
FORCEPROP 1 LAST MATERIAL IC
J 0
(7450 -365);
DISPLAY 0.723404 (7450 -365);
PAINT GREEN (7450 -365);
FORCEPROP 2 LAST PACK_TYPE SMLF
J 0
(7450 -225);
DISPLAY 1.021277 (7450 -225);
FORCEPROP 1 LAST PART_NUMBER AL002G07006
J 0
(7450 -315);
DISPLAY 0.723404 (7450 -315);
PAINT GREEN (7450 -315);
DISPLAY INVISIBLE (7450 -315);
FORCEPROP 1 LAST PATH I5
J 0
(7775 -370);
DISPLAY 0.723404 (7775 -370);
PAINT GREEN (7775 -370);
DISPLAY INVISIBLE (7775 -370);
FORCEPROP 2 LAST CDS_LIB pure_quanta
J 0
(7625 -475);
DISPLAY INVISIBLE (7625 -475);
FORCEPROP 1 LAST NEEDS_NO_SIZE TRUE
J 0
(7625 -475);
DISPLAY 0.468085 (7625 -475);
PAINT GREEN (7625 -475);
DISPLAY INVISIBLE (7625 -475);
FORCEADD TAP..1
R 2
(7675 4175);
FORCEPROP 3 LASTPIN (7725 4175) SIG_NAME P3E_CPU1_P4_TX_C_DN<3>
J 0
(7735 4185);
DISPLAY 0.659574 (7735 4185);
PAINT MONO (7735 4185);
DISPLAY INVISIBLE (7735 4185);
FORCEPROP 1 LASTPIN (7725 4175) BN 3
J 2
(7737 4183);
DISPLAY 0.680851 (7737 4183);
PAINT GREEN (7737 4183);
FORCEPROP 1 LAST PATH I50
J 2
(7677 4175);
DISPLAY 0.872340 (7677 4175);
PAINT GREEN (7677 4175);
DISPLAY INVISIBLE (7677 4175);
FORCEPROP 1 LAST HDL_TAP TRUE
J 2
(7350 4050);
DISPLAY 0.872340 (7350 4050);
PAINT GREEN (7350 4050);
DISPLAY INVISIBLE (7350 4050);
FORCEPROP 1 LAST BODY_TYPE PLUMBING
J 2
(7675 4225);
DISPLAY 0.872340 (7675 4225);
PAINT GREEN (7675 4225);
DISPLAY INVISIBLE (7675 4225);
FORCEPROP 2 LAST CDS_LIB standard
J 0
(7675 4175);
DISPLAY INVISIBLE (7675 4175);
FORCEADD Q_RES..2
(8575 225);
FORCEPROP 1 LAST LOCATION R3296
J 0
(8620 350);
DISPLAY 0.978723 (8620 350);
FORCEPROP 0 LAST $SEC 1
J 0
(8625 400);
DISPLAY 0.680851 (8625 400);
PAINT MONO (8625 400);
DISPLAY INVISIBLE (8625 400);
FORCEPROP 0 LAST CDS_SEC 1
J 0
(8625 400);
DISPLAY 1.021277 (8625 400);
DISPLAY INVISIBLE (8625 400);
FORCEPROP 1 LASTPIN (8575 325) $PN 1
J 0
(8580 287);
DISPLAY 0.787234 (8580 287);
PAINT MONO (8580 287);
FORCEPROP 1 LASTPIN (8575 125) $PN 2
J 0
(8580 135);
DISPLAY 0.787234 (8580 135);
PAINT MONO (8580 135);
FORCEPROP 1 LAST PACK_TYPE 0402LF
J 0
(8615 50);
DISPLAY 0.787234 (8615 50);
FORCEPROP 1 LAST TOLERANCE 1%
J 0
(8620 250);
DISPLAY 0.787234 (8620 250);
FORCEPROP 1 LAST VALUE 4.7K
J 0
(8620 300);
DISPLAY 0.787234 (8620 300);
FORCEPROP 1 LAST WATTAGE 1/16W
J 0
(8615 200);
DISPLAY 0.787234 (8615 200);
FORCEPROP 1 LAST MATERIAL CHIP
J 0
(8615 150);
DISPLAY 0.787234 (8615 150);
FORCEPROP 1 LAST PART_NUMBER CS24702FB06
J 0
(8615 100);
DISPLAY 0.787234 (8615 100);
DISPLAY INVISIBLE (8615 100);
FORCEPROP 1 LAST PATH I51
J 0
(8625 400);
DISPLAY 0.978723 (8625 400);
PAINT WHITE (8625 400);
DISPLAY INVISIBLE (8625 400);
FORCEPROP 2 LAST CDS_LIB pure_quanta
J 0
(8575 225);
DISPLAY INVISIBLE (8575 225);
FORCEADD UNIVERSAL_POWER..1
(8575 550);
FORCEPROP 3 LASTPIN (8575 500) SIG_NAME P3V3_AUX\g
J 0
(8585 510);
DISPLAY 0.659574 (8585 510);
PAINT MONO (8585 510);
DISPLAY INVISIBLE (8585 510);
FORCEPROP 1 LAST HDL_POWER P3V3_AUX
J 1
(8575 600);
DISPLAY 0.723404 (8575 600);
PAINT GREEN (8575 600);
FORCEPROP 1 LAST PATH I52
J 0
(8625 575);
DISPLAY 0.872340 (8625 575);
PAINT AQUA (8625 575);
DISPLAY INVISIBLE (8625 575);
FORCEPROP 2 LAST CDS_LIB pure_quanta_power
J 0
(8575 550);
DISPLAY INVISIBLE (8575 550);
FORCEADD 74LVC1G126SE7..1
(9300 1100);
FORCEPROP 1 LAST LOCATION U239
J 0
(9406 931);
DISPLAY 0.723404 (9406 931);
PAINT GREEN (9406 931);
FORCEPROP 0 LAST $SEC 1
J 0
(9425 975);
DISPLAY 0.680851 (9425 975);
PAINT MONO (9425 975);
DISPLAY INVISIBLE (9425 975);
FORCEPROP 0 LAST CDS_SEC 1
J 0
(9425 975);
DISPLAY 1.021277 (9425 975);
DISPLAY INVISIBLE (9425 975);
FORCEPROP 0 LASTPIN (9050 1150) $PN 2
J 2
(9040 1160);
DISPLAY 0.680851 (9040 1160);
PAINT MONO (9040 1160);
FORCEPROP 0 LASTPIN (9300 850) $PN 3
R 1
J 2
(9290 840);
DISPLAY 0.680851 (9290 840);
PAINT MONO (9290 840);
FORCEPROP 0 LASTPIN (9050 1050) $PN 1
J 2
(9040 1060);
DISPLAY 0.680851 (9040 1060);
PAINT MONO (9040 1060);
FORCEPROP 0 LASTPIN (9300 1350) $PN 5
R 1
J 0
(9290 1360);
DISPLAY 0.680851 (9290 1360);
PAINT MONO (9290 1360);
FORCEPROP 0 LASTPIN (9550 1100) $PN 4
J 0
(9560 1110);
DISPLAY 0.680851 (9560 1110);
PAINT MONO (9560 1110);
FORCEPROP 1 LAST MATERIAL IC
J 0
(9406 657);
DISPLAY 0.723404 (9406 657);
PAINT GREEN (9406 657);
FORCEPROP 2 LAST PART_TYPE SMLF
J 0
(9400 875);
DISPLAY 0.638298 (9400 875);
FORCEPROP 2 LAST VALUE 74LVC1G126SE-7
J 0
(9400 825);
DISPLAY 0.638298 (9400 825);
FORCEPROP 1 LAST PART_NUMBER AL1G0126009
J 0
(9406 784);
DISPLAY 0.723404 (9406 784);
PAINT GREEN (9406 784);
DISPLAY INVISIBLE (9406 784);
FORCEPROP 1 LAST PATH I53
J 0
(9300 1100);
DISPLAY 0.723404 (9300 1100);
PAINT GREEN (9300 1100);
DISPLAY INVISIBLE (9300 1100);
FORCEPROP 1 LAST NEEDS_NO_SIZE TRUE
J 0
(9300 1100);
DISPLAY 0.723404 (9300 1100);
PAINT GREEN (9300 1100);
DISPLAY INVISIBLE (9300 1100);
FORCEPROP 1 LAST CDS_LMAN_SYM_OUTLINE -100,100,100,-100
J 0
(9300 1100);
DISPLAY 0.468085 (9300 1100);
PAINT GREEN (9300 1100);
DISPLAY INVISIBLE (9300 1100);
FORCEPROP 2 LAST CDS_LIB pure_quanta
J 0
(9300 1100);
DISPLAY INVISIBLE (9300 1100);
FORCEADD UNIVERSAL_GND..1
(9300 700);
FORCEPROP 3 LASTPIN (9300 750) SIG_NAME GND\g
J 0
(9310 760);
DISPLAY 0.659574 (9310 760);
PAINT MONO (9310 760);
DISPLAY INVISIBLE (9310 760);
FORCEPROP 1 LAST PATH I54
J 0
(9375 700);
DISPLAY 0.872340 (9375 700);
PAINT AQUA (9375 700);
DISPLAY INVISIBLE (9375 700);
FORCEPROP 1 LAST HDL_POWER GND
J 1
(9325 625);
DISPLAY 0.872340 (9325 625);
PAINT GREEN (9325 625);
DISPLAY INVISIBLE (9325 625);
FORCEPROP 2 LAST CDS_LIB pure_quanta_power
J 0
(9300 700);
DISPLAY INVISIBLE (9300 700);
FORCEADD UNIVERSAL_GND..1
(9550 1200);
FORCEPROP 3 LASTPIN (9550 1250) SIG_NAME GND\g
J 0
(9560 1260);
DISPLAY 0.659574 (9560 1260);
PAINT MONO (9560 1260);
DISPLAY INVISIBLE (9560 1260);
FORCEPROP 1 LAST PATH I55
J 0
(9625 1200);
DISPLAY 0.872340 (9625 1200);
PAINT AQUA (9625 1200);
DISPLAY INVISIBLE (9625 1200);
FORCEPROP 1 LAST HDL_POWER GND
J 1
(9575 1125);
DISPLAY 0.872340 (9575 1125);
PAINT GREEN (9575 1125);
DISPLAY INVISIBLE (9575 1125);
FORCEPROP 2 LAST CDS_LIB pure_quanta_power
J 0
(9550 1200);
DISPLAY INVISIBLE (9550 1200);
FORCEADD Q_CAP..1
(9550 1450);
FORCEPROP 1 LAST LOCATION C1873
J 0
(9600 1550);
DISPLAY 0.978723 (9600 1550);
FORCEPROP 0 LAST $SEC 1
J 0
(9600 1600);
DISPLAY 0.680851 (9600 1600);
PAINT MONO (9600 1600);
DISPLAY INVISIBLE (9600 1600);
FORCEPROP 0 LAST CDS_SEC 1
J 0
(9600 1600);
DISPLAY 1.021277 (9600 1600);
DISPLAY INVISIBLE (9600 1600);
FORCEPROP 1 LASTPIN (9550 1550) $PN 1
J 0
(9560 1530);
DISPLAY 0.787234 (9560 1530);
PAINT MONO (9560 1530);
FORCEPROP 1 LASTPIN (9550 1350) $PN 2
J 0
(9560 1330);
DISPLAY 0.787234 (9560 1330);
PAINT MONO (9560 1330);
FORCEPROP 1 LAST MATERIAL X7R
J 0
(9600 1350);
DISPLAY 0.617021 (9600 1350);
FORCEPROP 1 LAST VALUE 0.1UF
J 0
(9600 1500);
DISPLAY 0.617021 (9600 1500);
FORCEPROP 1 LAST PACK_TYPE 0402
J 0
(9600 1250);
DISPLAY 0.617021 (9600 1250);
FORCEPROP 1 LAST TOLERANCE 10%
J 0
(9600 1400);
DISPLAY 0.617021 (9600 1400);
FORCEPROP 1 LAST VOLTAGE 25V
J 0
(9600 1450);
DISPLAY 0.617021 (9600 1450);
FORCEPROP 1 LAST PART_NUMBER CH4104K1B00
J 0
(9600 1300);
DISPLAY 0.617021 (9600 1300);
DISPLAY INVISIBLE (9600 1300);
FORCEPROP 1 LAST PATH I56
J 0
(9600 1600);
DISPLAY 0.978723 (9600 1600);
PAINT WHITE (9600 1600);
DISPLAY INVISIBLE (9600 1600);
FORCEPROP 2 LAST BOM_COST VR_SYSTEM 
J 0
(9600 1600);
DISPLAY 0.680851 (9600 1600);
DISPLAY INVISIBLE (9600 1600);
FORCEPROP 2 LAST CDS_LIB pure_quanta
J 0
(9550 1450);
DISPLAY INVISIBLE (9550 1450);
FORCEADD UNIVERSAL_POWER..1
(9300 1800);
FORCEPROP 3 LASTPIN (9300 1750) SIG_NAME P3V3_AUX\g
J 0
(9310 1760);
DISPLAY 0.659574 (9310 1760);
PAINT MONO (9310 1760);
DISPLAY INVISIBLE (9310 1760);
FORCEPROP 1 LAST HDL_POWER P3V3_AUX
J 1
(9300 1850);
DISPLAY 0.723404 (9300 1850);
PAINT GREEN (9300 1850);
FORCEPROP 1 LAST PATH I57
J 0
(9350 1825);
DISPLAY 0.872340 (9350 1825);
PAINT AQUA (9350 1825);
DISPLAY INVISIBLE (9350 1825);
FORCEPROP 2 LAST CDS_LIB pure_quanta_power
J 0
(9300 1800);
DISPLAY INVISIBLE (9300 1800);
FORCEADD Q_RES..2
R 2
(10675 425);
FORCEPROP 1 LAST LOCATION R3298
J 2
(10630 550);
DISPLAY 0.978723 (10630 550);
FORCEPROP 0 LAST $SEC 1
J 0
(10650 600);
DISPLAY 0.680851 (10650 600);
PAINT MONO (10650 600);
DISPLAY INVISIBLE (10650 600);
FORCEPROP 0 LAST CDS_SEC 1
J 0
(10650 600);
DISPLAY 1.021277 (10650 600);
DISPLAY INVISIBLE (10650 600);
FORCEPROP 1 LASTPIN (10675 525) $PN 1
J 2
(10670 487);
DISPLAY 0.787234 (10670 487);
PAINT MONO (10670 487);
FORCEPROP 1 LASTPIN (10675 325) $PN 2
J 2
(10670 335);
DISPLAY 0.787234 (10670 335);
PAINT MONO (10670 335);
FORCEPROP 1 LAST VALUE 10K
J 2
(10630 500);
DISPLAY 0.510638 (10630 500);
FORCEPROP 1 LAST PACK_TYPE 0402LF
J 2
(10635 250);
DISPLAY 0.510638 (10635 250);
FORCEPROP 1 LAST MATERIAL CHIP
J 2
(10635 350);
DISPLAY 0.510638 (10635 350);
FORCEPROP 1 LAST TOLERANCE 1%
J 2
(10630 450);
DISPLAY 0.510638 (10630 450);
FORCEPROP 1 LAST WATTAGE 1/16W
J 2
(10635 400);
DISPLAY 0.510638 (10635 400);
FORCEPROP 1 LAST PART_NUMBER CS31002FB08
J 2
(10635 300);
DISPLAY 0.510638 (10635 300);
DISPLAY INVISIBLE (10635 300);
FORCEPROP 1 LAST PATH I58
J 2
(10625 600);
DISPLAY 0.978723 (10625 600);
PAINT WHITE (10625 600);
DISPLAY INVISIBLE (10625 600);
FORCEPROP 2 LAST CDS_LIB pure_quanta
J 0
(10675 425);
DISPLAY INVISIBLE (10675 425);
FORCEADD UNIVERSAL_GND..1
(10250 600);
FORCEPROP 3 LASTPIN (10250 650) SIG_NAME GND\g
J 0
(10260 660);
DISPLAY 0.659574 (10260 660);
PAINT MONO (10260 660);
DISPLAY INVISIBLE (10260 660);
FORCEPROP 1 LAST PATH I59
J 0
(10325 600);
DISPLAY 0.872340 (10325 600);
PAINT AQUA (10325 600);
DISPLAY INVISIBLE (10325 600);
FORCEPROP 1 LAST HDL_POWER GND
J 1
(10275 525);
DISPLAY 0.872340 (10275 525);
PAINT GREEN (10275 525);
DISPLAY INVISIBLE (10275 525);
FORCEPROP 2 LAST CDS_LIB pure_quanta_power
J 0
(10250 600);
DISPLAY INVISIBLE (10250 600);
FORCEADD Q_CAP..1
(8000 -825);
FORCEPROP 1 LAST LOCATION C2007
J 0
(8050 -725);
DISPLAY 0.978723 (8050 -725);
FORCEPROP 0 LAST $SEC 1
J 0
(8050 -675);
DISPLAY 0.680851 (8050 -675);
PAINT MONO (8050 -675);
DISPLAY INVISIBLE (8050 -675);
FORCEPROP 0 LAST CDS_SEC 1
J 0
(8050 -675);
DISPLAY 1.021277 (8050 -675);
DISPLAY INVISIBLE (8050 -675);
FORCEPROP 1 LASTPIN (8000 -725) $PN 1
J 0
(8010 -745);
DISPLAY 0.787234 (8010 -745);
PAINT MONO (8010 -745);
FORCEPROP 1 LASTPIN (8000 -925) $PN 2
J 0
(8010 -945);
DISPLAY 0.787234 (8010 -945);
PAINT MONO (8010 -945);
FORCEPROP 1 LAST PACK_TYPE C0402
J 0
(8050 -975);
DISPLAY 0.638298 (8050 -975);
FORCEPROP 1 LAST MATERIAL X6S
J 0
(8050 -925);
DISPLAY 0.638298 (8050 -925);
FORCEPROP 1 LAST VOLTAGE 25V
J 0
(8050 -825);
DISPLAY 0.638298 (8050 -825);
FORCEPROP 1 LAST TOLERANCE 10%
J 0
(8050 -875);
DISPLAY 0.638298 (8050 -875);
FORCEPROP 1 LAST VALUE 1UF
J 0
(8050 -775);
DISPLAY 0.638298 (8050 -775);
FORCEPROP 1 LAST PART_NUMBER CH5104KEB02
J 0
(8050 -1025);
DISPLAY 0.510638 (8050 -1025);
DISPLAY INVISIBLE (8050 -1025);
FORCEPROP 1 LAST PATH I6
J 0
(8050 -675);
DISPLAY 0.978723 (8050 -675);
PAINT WHITE (8050 -675);
DISPLAY INVISIBLE (8050 -675);
FORCEPROP 2 LAST CDS_LIB pure_quanta
J 0
(8000 -825);
DISPLAY INVISIBLE (8000 -825);
FORCEPROP 2 LAST BOM_COST VR_SYSTEM 
J 0
(8050 -675);
DISPLAY 0.680851 (8050 -675);
DISPLAY INVISIBLE (8050 -675);
FORCEADD Q_RES..2
R 2
(10250 850);
FORCEPROP 1 LAST LOCATION R3297
J 2
(10205 975);
DISPLAY 0.978723 (10205 975);
FORCEPROP 0 LAST $SEC 1
J 0
(10225 1025);
DISPLAY 0.680851 (10225 1025);
PAINT MONO (10225 1025);
DISPLAY INVISIBLE (10225 1025);
FORCEPROP 0 LAST CDS_SEC 1
J 0
(10225 1025);
DISPLAY 1.021277 (10225 1025);
DISPLAY INVISIBLE (10225 1025);
FORCEPROP 1 LASTPIN (10250 950) $PN 1
J 2
(10245 912);
DISPLAY 0.787234 (10245 912);
PAINT MONO (10245 912);
FORCEPROP 1 LASTPIN (10250 750) $PN 2
J 2
(10245 760);
DISPLAY 0.787234 (10245 760);
PAINT MONO (10245 760);
FORCEPROP 1 LAST VALUE 10K
J 2
(10205 925);
DISPLAY 0.510638 (10205 925);
FORCEPROP 1 LAST PACK_TYPE 0402LF
J 2
(10210 675);
DISPLAY 0.510638 (10210 675);
FORCEPROP 1 LAST MATERIAL CHIP
J 2
(10210 775);
DISPLAY 0.510638 (10210 775);
FORCEPROP 1 LAST WATTAGE 1/16W
J 2
(10210 825);
DISPLAY 0.510638 (10210 825);
FORCEPROP 1 LAST TOLERANCE 1%
J 2
(10205 875);
DISPLAY 0.510638 (10205 875);
FORCEPROP 1 LAST PART_NUMBER CS31002FB08
J 2
(10210 725);
DISPLAY 0.510638 (10210 725);
DISPLAY INVISIBLE (10210 725);
FORCEPROP 1 LAST PATH I60
J 2
(10200 1025);
DISPLAY 0.978723 (10200 1025);
PAINT WHITE (10200 1025);
DISPLAY INVISIBLE (10200 1025);
FORCEPROP 2 LAST CDS_LIB pure_quanta
J 0
(10250 850);
DISPLAY INVISIBLE (10250 850);
FORCEADD UNIVERSAL_POWER..1
(10675 625);
FORCEPROP 3 LASTPIN (10675 575) SIG_NAME P3V3_AUX\g
J 0
(10685 585);
DISPLAY 0.659574 (10685 585);
PAINT MONO (10685 585);
DISPLAY INVISIBLE (10685 585);
FORCEPROP 1 LAST HDL_POWER P3V3_AUX
J 1
(10675 675);
DISPLAY 0.723404 (10675 675);
PAINT GREEN (10675 675);
FORCEPROP 1 LAST PATH I61
J 0
(10725 650);
DISPLAY 0.872340 (10725 650);
PAINT AQUA (10725 650);
DISPLAY INVISIBLE (10725 650);
FORCEPROP 2 LAST CDS_LIB pure_quanta_power
J 0
(10675 625);
DISPLAY INVISIBLE (10675 625);
FORCEADD Q_RES..1
(10950 175);
FORCEPROP 1 LAST LOCATION R5377
J 0
(10825 200);
DISPLAY 0.723404 (10825 200);
FORCEPROP 0 LAST $SEC 1
J 0
(10825 250);
DISPLAY INVISIBLE (10825 250);
FORCEPROP 0 LAST CDS_SEC 1
J 0
(10825 250);
DISPLAY INVISIBLE (10825 250);
FORCEPROP 1 LASTPIN (10850 175) $PN 1
J 0
(10862 187);
DISPLAY 0.787234 (10862 187);
PAINT MONO (10862 187);
DISPLAY INVISIBLE (10862 187);
FORCEPROP 1 LASTPIN (11050 175) $PN 2
J 0
(11012 187);
DISPLAY 0.787234 (11012 187);
PAINT MONO (11012 187);
DISPLAY INVISIBLE (11012 187);
FORCEPROP 1 LAST TOLERANCE 5%
J 0
(10825 125);
DISPLAY 0.723404 (10825 125);
FORCEPROP 1 LAST PACK_TYPE 0402LF
J 0
(11025 175);
DISPLAY 0.723404 (11025 175);
FORCEPROP 1 LAST WATTAGE 1/16W
J 2
(11425 175);
DISPLAY 0.723404 (11425 175);
FORCEPROP 1 LAST VALUE 0
J 2
(10775 125);
DISPLAY 0.723404 (10775 125);
FORCEPROP 1 LAST MATERIAL CHIP
J 0
(11025 125);
DISPLAY 0.723404 (11025 125);
FORCEPROP 1 LAST PART_NUMBER CS00002JB13
J 0
(11025 75);
DISPLAY 0.723404 (11025 75);
DISPLAY INVISIBLE (11025 75);
FORCEPROP 1 LAST PATH I62
J 0
(10900 325);
DISPLAY 0.978723 (10900 325);
PAINT WHITE (10900 325);
DISPLAY INVISIBLE (10900 325);
FORCEPROP 2 LAST CDS_LIB pure_quanta
J 0
(10950 175);
DISPLAY INVISIBLE (10950 175);
FORCEADD OFFPAGE..2
(11450 1100);
FORCEPROP 2 LAST $XR0 85 
J 0
(11639 1100);
DISPLAY 0.638298 (11639 1100);
PAINT MONO (11639 1100);
FORCEPROP 2 LAST $XR1 150 
J 0
(11729 1100);
DISPLAY 0.638298 (11729 1100);
PAINT MONO (11729 1100);
FORCEPROP 2 LAST PATH I63
J 0
(11775 1150);
DISPLAY 0.680851 (11775 1150);
DISPLAY INVISIBLE (11775 1150);
FORCEPROP 1 LAST COMMENT_BODY TRUE
J 0
(11405 1005);
DISPLAY 0.872340 (11405 1005);
PAINT GREEN (11405 1005);
DISPLAY INVISIBLE (11405 1005);
FORCEPROP 1 LAST OFFPAGE TRUE
J 0
(11775 975);
DISPLAY 0.872340 (11775 975);
PAINT AQUA (11775 975);
DISPLAY INVISIBLE (11775 975);
FORCEPROP 2 LAST CDS_LIB standard
J 0
(11450 1100);
DISPLAY INVISIBLE (11450 1100);
FORCEADD OFFPAGE..4
(10575 2925);
FORCEPROP 2 LAST $XR0 148 
J 0
(10791 2925);
DISPLAY 0.638298 (10791 2925);
PAINT MONO (10791 2925);
FORCEPROP 2 LAST PATH I64
J 0
(10800 2975);
DISPLAY 0.680851 (10800 2975);
DISPLAY INVISIBLE (10800 2975);
FORCEPROP 1 LAST COMMENT_BODY TRUE
J 0
(10550 2825);
DISPLAY 0.872340 (10550 2825);
PAINT GREEN (10550 2825);
DISPLAY INVISIBLE (10550 2825);
FORCEPROP 1 LAST OFFPAGE TRUE
J 0
(10900 2800);
DISPLAY 0.872340 (10900 2800);
DISPLAY INVISIBLE (10900 2800);
FORCEPROP 2 LAST CDS_LIB standard
J 0
(10575 2925);
DISPLAY INVISIBLE (10575 2925);
FORCEADD OFFPAGE..3
(10575 2975);
FORCEPROP 2 LAST $XR0 148 
J 0
(10789 2975);
DISPLAY 0.638298 (10789 2975);
PAINT MONO (10789 2975);
FORCEPROP 2 LAST PATH I65
J 0
(10800 3025);
DISPLAY 0.680851 (10800 3025);
DISPLAY INVISIBLE (10800 3025);
FORCEPROP 1 LAST COMMENT_BODY TRUE
J 0
(10525 2875);
DISPLAY 0.872340 (10525 2875);
PAINT GREEN (10525 2875);
DISPLAY INVISIBLE (10525 2875);
FORCEPROP 1 LAST OFFPAGE TRUE
J 0
(10900 2850);
DISPLAY 0.872340 (10900 2850);
PAINT GREEN (10900 2850);
DISPLAY INVISIBLE (10900 2850);
FORCEPROP 2 LAST CDS_LIB standard
J 0
(10575 2975);
PAINT MONO (10575 2975);
DISPLAY INVISIBLE (10575 2975);
FORCEADD Q_RES..1
(10550 3200);
FORCEPROP 1 LAST LOCATION R1396
J 0
(10325 3200);
DISPLAY 0.638298 (10325 3200);
FORCEPROP 2 LAST $SEC 1
J 0
(10500 3400);
DISPLAY 0.680851 (10500 3400);
PAINT MONO (10500 3400);
DISPLAY INVISIBLE (10500 3400);
FORCEPROP 2 LAST CDS_SEC 1
J 0
(10500 3400);
DISPLAY 1.021277 (10500 3400);
DISPLAY INVISIBLE (10500 3400);
FORCEPROP 1 LASTPIN (10450 3200) $PN 1
J 0
(10462 3212);
DISPLAY 0.787234 (10462 3212);
FORCEPROP 1 LASTPIN (10650 3200) $PN 2
J 0
(10612 3212);
DISPLAY 0.787234 (10612 3212);
FORCEPROP 1 LAST WATTAGE 1/16W
J 2
(10700 3300);
DISPLAY 0.404255 (10700 3300);
FORCEPROP 1 LAST TOLERANCE 1%
J 0
(10775 3200);
DISPLAY 0.638298 (10775 3200);
FORCEPROP 1 LAST MATERIAL CHIP
J 0
(10850 3200);
DISPLAY 0.638298 (10850 3200);
FORCEPROP 1 LAST PACK_TYPE 0402LF
J 0
(10400 3300);
DISPLAY 0.404255 (10400 3300);
FORCEPROP 1 LAST VALUE 10K
J 2
(10750 3200);
DISPLAY 0.638298 (10750 3200);
FORCEPROP 1 LAST PART_NUMBER CS31002FB08
J 0
(10400 3275);
DISPLAY 0.404255 (10400 3275);
DISPLAY INVISIBLE (10400 3275);
FORCEPROP 1 LAST PATH I66
J 0
(10500 3350);
DISPLAY 0.978723 (10500 3350);
PAINT WHITE (10500 3350);
DISPLAY INVISIBLE (10500 3350);
FORCEPROP 2 LAST CDS_LIB pure_quanta
J 0
(10550 3200);
PAINT MONO (10550 3200);
DISPLAY INVISIBLE (10550 3200);
FORCEADD OFFPAGE..2
(10575 3525);
FORCEPROP 2 LAST $XR0 144 
J 0
(10764 3525);
DISPLAY 0.638298 (10764 3525);
PAINT MONO (10764 3525);
FORCEPROP 2 LAST PATH I68
J 0
(10775 3575);
DISPLAY 0.680851 (10775 3575);
DISPLAY INVISIBLE (10775 3575);
FORCEPROP 1 LAST COMMENT_BODY TRUE
J 0
(10530 3430);
DISPLAY 0.872340 (10530 3430);
PAINT GREEN (10530 3430);
DISPLAY INVISIBLE (10530 3430);
FORCEPROP 1 LAST OFFPAGE TRUE
J 0
(10900 3400);
DISPLAY 0.872340 (10900 3400);
PAINT GREEN (10900 3400);
DISPLAY INVISIBLE (10900 3400);
FORCEPROP 2 LAST CDS_LIB standard
J 0
(10575 3525);
DISPLAY INVISIBLE (10575 3525);
FORCEADD OFFPAGE..4
(10575 3625);
FORCEPROP 2 LAST $XR0 67 
J 0
(10761 3625);
DISPLAY 0.638298 (10761 3625);
PAINT MONO (10761 3625);
FORCEPROP 2 LAST PATH I69
J 0
(10775 3675);
DISPLAY 0.680851 (10775 3675);
DISPLAY INVISIBLE (10775 3675);
FORCEPROP 1 LAST COMMENT_BODY TRUE
J 0
(10550 3525);
DISPLAY 0.872340 (10550 3525);
PAINT GREEN (10550 3525);
DISPLAY INVISIBLE (10550 3525);
FORCEPROP 1 LAST OFFPAGE TRUE
J 0
(10900 3500);
DISPLAY 0.872340 (10900 3500);
DISPLAY INVISIBLE (10900 3500);
FORCEPROP 2 LAST CDS_LIB standard
J 0
(10575 3625);
PAINT MONO (10575 3625);
DISPLAY INVISIBLE (10575 3625);
FORCEADD UNIVERSAL_POWER..1
(8000 -275);
FORCEPROP 3 LASTPIN (8000 -325) SIG_NAME P3V3_AUX\g
J 0
(8010 -315);
DISPLAY 0.659574 (8010 -315);
PAINT MONO (8010 -315);
DISPLAY INVISIBLE (8010 -315);
FORCEPROP 1 LAST HDL_POWER P3V3_AUX
J 1
(8000 -225);
DISPLAY 0.723404 (8000 -225);
PAINT GREEN (8000 -225);
FORCEPROP 1 LAST PATH I7
J 0
(8050 -250);
DISPLAY 0.872340 (8050 -250);
PAINT AQUA (8050 -250);
DISPLAY INVISIBLE (8050 -250);
FORCEPROP 2 LAST CDS_LIB pure_quanta_power
J 0
(8000 -275);
DISPLAY INVISIBLE (8000 -275);
FORCEADD OFFPAGE..4
(10575 3675);
FORCEPROP 2 LAST $XR0 67 
J 0
(10761 3675);
DISPLAY 0.638298 (10761 3675);
PAINT MONO (10761 3675);
FORCEPROP 2 LAST PATH I70
J 0
(10775 3725);
DISPLAY 0.680851 (10775 3725);
DISPLAY INVISIBLE (10775 3725);
FORCEPROP 1 LAST COMMENT_BODY TRUE
J 0
(10550 3575);
DISPLAY 0.872340 (10550 3575);
PAINT GREEN (10550 3575);
DISPLAY INVISIBLE (10550 3575);
FORCEPROP 1 LAST OFFPAGE TRUE
J 0
(10900 3550);
DISPLAY 0.872340 (10900 3550);
DISPLAY INVISIBLE (10900 3550);
FORCEPROP 2 LAST CDS_LIB standard
J 0
(10575 3675);
PAINT MONO (10575 3675);
DISPLAY INVISIBLE (10575 3675);
FORCEADD OFFPAGE..2
(10575 3775);
FORCEPROP 2 LAST $XR0 53 
J 0
(10764 3775);
DISPLAY 0.638298 (10764 3775);
PAINT MONO (10764 3775);
FORCEPROP 2 LAST PATH I71
J 0
(10775 3825);
DISPLAY 0.680851 (10775 3825);
DISPLAY INVISIBLE (10775 3825);
FORCEPROP 1 LAST COMMENT_BODY TRUE
J 0
(10530 3680);
DISPLAY 0.872340 (10530 3680);
PAINT GREEN (10530 3680);
DISPLAY INVISIBLE (10530 3680);
FORCEPROP 1 LAST OFFPAGE TRUE
J 0
(10900 3650);
DISPLAY 0.872340 (10900 3650);
PAINT GREEN (10900 3650);
DISPLAY INVISIBLE (10900 3650);
FORCEPROP 2 LAST CDS_LIB standard
J 0
(10575 3775);
PAINT MONO (10575 3775);
DISPLAY INVISIBLE (10575 3775);
FORCEADD OFFPAGE..2
(10575 3825);
FORCEPROP 2 LAST $XR0 53 
J 0
(10764 3825);
DISPLAY 0.638298 (10764 3825);
PAINT MONO (10764 3825);
FORCEPROP 2 LAST PATH I72
J 0
(10775 3875);
DISPLAY 0.680851 (10775 3875);
DISPLAY INVISIBLE (10775 3875);
FORCEPROP 1 LAST COMMENT_BODY TRUE
J 0
(10530 3730);
DISPLAY 0.872340 (10530 3730);
PAINT GREEN (10530 3730);
DISPLAY INVISIBLE (10530 3730);
FORCEPROP 1 LAST OFFPAGE TRUE
J 0
(10900 3700);
DISPLAY 0.872340 (10900 3700);
PAINT GREEN (10900 3700);
DISPLAY INVISIBLE (10900 3700);
FORCEPROP 2 LAST CDS_LIB standard
J 0
(10575 3825);
PAINT MONO (10575 3825);
DISPLAY INVISIBLE (10575 3825);
FORCEADD UNIVERSAL_POWER..1
(11125 3275);
FORCEPROP 3 LASTPIN (11125 3225) SIG_NAME P3V3_AUX\g
J 0
(11135 3235);
DISPLAY 0.659574 (11135 3235);
PAINT MONO (11135 3235);
DISPLAY INVISIBLE (11135 3235);
FORCEPROP 1 LAST HDL_POWER P3V3_AUX
J 1
(11125 3325);
DISPLAY 0.702128 (11125 3325);
PAINT GREEN (11125 3325);
FORCEPROP 1 LAST PATH I73
J 0
(11175 3300);
DISPLAY 0.872340 (11175 3300);
PAINT AQUA (11175 3300);
DISPLAY INVISIBLE (11175 3300);
FORCEPROP 2 LAST CDS_LIB pure_quanta_power
J 0
(11125 3275);
PAINT MONO (11125 3275);
DISPLAY INVISIBLE (11125 3275);
FORCEADD UNIVERSAL_POWER..1
(9425 4575);
FORCEPROP 3 LASTPIN (9425 4525) SIG_NAME P3V3_M2_0\g
J 0
(9435 4535);
DISPLAY 0.659574 (9435 4535);
PAINT MONO (9435 4535);
DISPLAY INVISIBLE (9435 4535);
FORCEPROP 1 LAST HDL_POWER P3V3_M2_0
J 1
(9425 4625);
DISPLAY 0.872340 (9425 4625);
PAINT GREEN (9425 4625);
FORCEPROP 1 LAST PATH I75
J 0
(9475 4600);
DISPLAY 0.872340 (9475 4600);
PAINT AQUA (9475 4600);
DISPLAY INVISIBLE (9475 4600);
FORCEPROP 2 LAST CDS_LIB pure_quanta_power
J 0
(9425 4575);
DISPLAY INVISIBLE (9425 4575);
FORCEADD UNIVERSAL_POWER..1
(11225 4575);
FORCEPROP 3 LASTPIN (11225 4525) SIG_NAME P3V3_M2_0\g
J 0
(11235 4535);
DISPLAY 0.659574 (11235 4535);
PAINT MONO (11235 4535);
DISPLAY INVISIBLE (11235 4535);
FORCEPROP 1 LAST HDL_POWER P3V3_M2_0
J 1
(11225 4625);
DISPLAY 0.872340 (11225 4625);
PAINT GREEN (11225 4625);
FORCEPROP 1 LAST PATH I76
J 0
(11275 4600);
DISPLAY 0.872340 (11275 4600);
PAINT AQUA (11275 4600);
DISPLAY INVISIBLE (11275 4600);
FORCEPROP 2 LAST CDS_LIB pure_quanta_power
J 0
(11225 4575);
PAINT MONO (11225 4575);
DISPLAY INVISIBLE (11225 4575);
FORCEADD Q_CAP..1
(11225 4200);
FORCEPROP 1 LAST LOCATION C1920
J 0
(11275 4300);
DISPLAY 0.978723 (11275 4300);
FORCEPROP 2 LAST $SEC 1
J 0
(11275 4400);
DISPLAY 0.680851 (11275 4400);
PAINT MONO (11275 4400);
DISPLAY INVISIBLE (11275 4400);
FORCEPROP 2 LAST CDS_SEC 1
J 0
(11275 4400);
DISPLAY 1.021277 (11275 4400);
DISPLAY INVISIBLE (11275 4400);
FORCEPROP 1 LASTPIN (11225 4300) $PN 1
J 0
(11235 4280);
DISPLAY 0.787234 (11235 4280);
FORCEPROP 1 LASTPIN (11225 4100) $PN 2
J 0
(11235 4080);
DISPLAY 0.787234 (11235 4080);
FORCEPROP 1 LAST VOLTAGE 6.3V
J 0
(11275 4200);
DISPLAY 0.638298 (11275 4200);
FORCEPROP 1 LAST VALUE 22UF
J 0
(11275 4250);
DISPLAY 0.638298 (11275 4250);
FORCEPROP 1 LAST MATERIAL X6S
J 0
(11275 4100);
DISPLAY 0.638298 (11275 4100);
FORCEPROP 1 LAST PACK_TYPE C0603
J 0
(11275 4000);
DISPLAY 0.638298 (11275 4000);
FORCEPROP 1 LAST TOLERANCE 20%
J 0
(11275 4150);
DISPLAY 0.638298 (11275 4150);
FORCEPROP 1 LAST PART_NUMBER CH6221ME900
J 0
(11275 4050);
DISPLAY 0.638298 (11275 4050);
DISPLAY INVISIBLE (11275 4050);
FORCEPROP 1 LAST PATH I77
J 0
(11275 4350);
DISPLAY 0.978723 (11275 4350);
PAINT WHITE (11275 4350);
DISPLAY INVISIBLE (11275 4350);
FORCEPROP 2 LAST CDS_LIB pure_quanta
J 0
(11225 4200);
PAINT MONO (11225 4200);
DISPLAY INVISIBLE (11225 4200);
FORCEADD Q_CAP..1
(11625 4200);
FORCEPROP 1 LAST LOCATION C1921
J 0
(11675 4300);
DISPLAY 0.978723 (11675 4300);
FORCEPROP 2 LAST $SEC 1
J 0
(11675 4400);
DISPLAY 0.680851 (11675 4400);
PAINT MONO (11675 4400);
DISPLAY INVISIBLE (11675 4400);
FORCEPROP 2 LAST CDS_SEC 1
J 0
(11675 4400);
DISPLAY 1.021277 (11675 4400);
DISPLAY INVISIBLE (11675 4400);
FORCEPROP 1 LASTPIN (11625 4300) $PN 1
J 0
(11635 4280);
DISPLAY 0.787234 (11635 4280);
FORCEPROP 1 LASTPIN (11625 4100) $PN 2
J 0
(11635 4080);
DISPLAY 0.787234 (11635 4080);
FORCEPROP 1 LAST VALUE 22UF
J 0
(11675 4250);
DISPLAY 0.638298 (11675 4250);
FORCEPROP 1 LAST PACK_TYPE C0603
J 0
(11675 4000);
DISPLAY 0.638298 (11675 4000);
FORCEPROP 1 LAST MATERIAL X6S
J 0
(11675 4100);
DISPLAY 0.638298 (11675 4100);
FORCEPROP 1 LAST TOLERANCE 20%
J 0
(11675 4150);
DISPLAY 0.638298 (11675 4150);
FORCEPROP 1 LAST VOLTAGE 6.3V
J 0
(11675 4200);
DISPLAY 0.638298 (11675 4200);
FORCEPROP 1 LAST PART_NUMBER CH6221ME900
J 0
(11675 4050);
DISPLAY 0.638298 (11675 4050);
DISPLAY INVISIBLE (11675 4050);
FORCEPROP 1 LAST PATH I78
J 0
(11675 4350);
DISPLAY 0.978723 (11675 4350);
PAINT WHITE (11675 4350);
DISPLAY INVISIBLE (11675 4350);
FORCEPROP 2 LAST CDS_LIB pure_quanta
J 0
(11625 4200);
PAINT MONO (11625 4200);
DISPLAY INVISIBLE (11625 4200);
FORCEADD Q_CAP..1
(12025 4200);
FORCEPROP 1 LAST LOCATION C9922
J 0
(12075 4300);
DISPLAY 0.978723 (12075 4300);
FORCEPROP 2 LAST $SEC 1
J 0
(12075 4400);
DISPLAY 0.680851 (12075 4400);
PAINT MONO (12075 4400);
DISPLAY INVISIBLE (12075 4400);
FORCEPROP 2 LAST CDS_SEC 1
J 0
(12075 4400);
DISPLAY 1.021277 (12075 4400);
DISPLAY INVISIBLE (12075 4400);
FORCEPROP 1 LASTPIN (12025 4300) $PN 1
J 0
(12035 4280);
DISPLAY 0.787234 (12035 4280);
FORCEPROP 1 LASTPIN (12025 4100) $PN 2
J 0
(12035 4080);
DISPLAY 0.787234 (12035 4080);
FORCEPROP 1 LAST VALUE 22UF
J 0
(12075 4250);
DISPLAY 0.638298 (12075 4250);
FORCEPROP 1 LAST TOLERANCE 20%
J 0
(12075 4150);
DISPLAY 0.638298 (12075 4150);
FORCEPROP 1 LAST VOLTAGE 6.3V
J 0
(12075 4200);
DISPLAY 0.638298 (12075 4200);
FORCEPROP 1 LAST PACK_TYPE C0603
J 0
(12075 4000);
DISPLAY 0.638298 (12075 4000);
FORCEPROP 1 LAST MATERIAL X6S
J 0
(12075 4100);
DISPLAY 0.638298 (12075 4100);
FORCEPROP 1 LAST PART_NUMBER CH6221ME900
J 0
(12075 4050);
DISPLAY 0.638298 (12075 4050);
DISPLAY INVISIBLE (12075 4050);
FORCEPROP 1 LAST PATH I79
J 0
(12075 4350);
DISPLAY 0.978723 (12075 4350);
PAINT WHITE (12075 4350);
DISPLAY INVISIBLE (12075 4350);
FORCEPROP 2 LAST CDS_LIB pure_quanta
J 0
(12025 4200);
PAINT MONO (12025 4200);
DISPLAY INVISIBLE (12025 4200);
FORCEADD MOSFET_NCH_DUAL..1
(9750 -125);
FORCEPROP 1 LAST LOCATION Q95
J 0
(9901 -151);
DISPLAY 0.723404 (9901 -151);
PAINT GREEN (9901 -151);
FORCEPROP 2 LAST SEC 1
J 0
(9925 0);
DISPLAY 0.680851 (9925 0);
PAINT MONO (9925 0);
DISPLAY INVISIBLE (9925 0);
FORCEPROP 2 LASTPIN (9800 75) $PN 6
R 1
J 0
(9790 85);
DISPLAY 0.680851 (9790 85);
PAINT MONO (9790 85);
FORCEPROP 2 LASTPIN (9550 -175) $PN 2
J 2
(9540 -165);
DISPLAY 0.680851 (9540 -165);
PAINT MONO (9540 -165);
FORCEPROP 2 LASTPIN (9800 -325) $PN 1
R 1
J 2
(9790 -335);
DISPLAY 0.680851 (9790 -335);
PAINT MONO (9790 -335);
FORCEPROP 1 LAST MATERIAL IC
J 0
(9901 -276);
DISPLAY 0.723404 (9901 -276);
PAINT GREEN (9901 -276);
FORCEPROP 2 LAST PART_TYPE SMLF
J 0
(9925 -50);
DISPLAY 0.680851 (9925 -50);
FORCEPROP 2 LAST VALUE PJT138K
J 0
(9925 -100);
DISPLAY 0.680851 (9925 -100);
FORCEPROP 1 LAST PART_NUMBER BAM138K0003
J 0
(9901 -211);
DISPLAY 0.723404 (9901 -211);
PAINT GREEN (9901 -211);
DISPLAY INVISIBLE (9901 -211);
FORCEPROP 1 LAST PATH I8
J 0
(9750 -125);
DISPLAY 0.723404 (9750 -125);
PAINT GREEN (9750 -125);
DISPLAY INVISIBLE (9750 -125);
FORCEPROP 1 LAST NEEDS_NO_SIZE TRUE
J 0
(9750 -126);
DISPLAY 0.468085 (9750 -126);
PAINT GREEN (9750 -126);
DISPLAY INVISIBLE (9750 -126);
FORCEPROP 2 LAST SEC_TYPE 
J 0
(9925 0);
DISPLAY 1.021277 (9925 0);
DISPLAY INVISIBLE (9925 0);
FORCEPROP 1 LAST CDS_LMAN_SYM_OUTLINE -150,150,150,-150
J 0
(9750 -125);
DISPLAY 0.468085 (9750 -125);
PAINT GREEN (9750 -125);
DISPLAY INVISIBLE (9750 -125);
FORCEPROP 2 LAST CDS_LIB pure_quanta
J 0
(9750 -125);
DISPLAY INVISIBLE (9750 -125);
FORCEADD OFFPAGE..5
(12450 3075);
FORCEPROP 2 LAST $XR0 144 
J 0
(12195 3075);
DISPLAY 0.638298 (12195 3075);
PAINT MONO (12195 3075);
FORCEPROP 2 LAST PATH I80
J 0
(12175 3125);
DISPLAY 0.680851 (12175 3125);
DISPLAY INVISIBLE (12175 3125);
FORCEPROP 1 LAST COMMENT_BODY TRUE
J 0
(12550 3000);
DISPLAY 0.872340 (12550 3000);
PAINT GREEN (12550 3000);
DISPLAY INVISIBLE (12550 3000);
FORCEPROP 1 LAST OFFPAGE TRUE
J 0
(12775 2950);
DISPLAY 0.872340 (12775 2950);
DISPLAY INVISIBLE (12775 2950);
FORCEPROP 2 LAST CDS_LIB standard
J 0
(12450 3075);
PAINT MONO (12450 3075);
DISPLAY INVISIBLE (12450 3075);
FORCEADD UNIVERSAL_GND..1
(13225 3850);
FORCEPROP 3 LASTPIN (13225 3900) SIG_NAME GND\g
J 0
(13235 3910);
DISPLAY 0.659574 (13235 3910);
PAINT MONO (13235 3910);
DISPLAY INVISIBLE (13235 3910);
FORCEPROP 1 LAST PATH I81
J 0
(13300 3850);
DISPLAY 0.872340 (13300 3850);
PAINT AQUA (13300 3850);
DISPLAY INVISIBLE (13300 3850);
FORCEPROP 1 LAST HDL_POWER GND
J 1
(13250 3775);
DISPLAY 0.872340 (13250 3775);
PAINT GREEN (13250 3775);
DISPLAY INVISIBLE (13250 3775);
FORCEPROP 2 LAST CDS_LIB pure_quanta_power
J 0
(13225 3850);
PAINT MONO (13225 3850);
DISPLAY INVISIBLE (13225 3850);
FORCEPROP 2 LAST CATEGORY LED
J 0
(13125 3925);
DISPLAY INVISIBLE (13125 3925);
FORCEADD UNIVERSAL_GND..1
(13300 2575);
FORCEPROP 3 LASTPIN (13300 2625) SIG_NAME GND\g
J 0
(13310 2635);
DISPLAY 0.659574 (13310 2635);
PAINT MONO (13310 2635);
DISPLAY INVISIBLE (13310 2635);
FORCEPROP 1 LAST PATH I82
J 0
(13375 2575);
DISPLAY 0.872340 (13375 2575);
PAINT AQUA (13375 2575);
DISPLAY INVISIBLE (13375 2575);
FORCEPROP 1 LAST HDL_POWER GND
J 1
(13325 2500);
DISPLAY 0.872340 (13325 2500);
PAINT GREEN (13325 2500);
DISPLAY INVISIBLE (13325 2500);
FORCEPROP 2 LAST CDS_LIB pure_quanta_power
J 0
(13300 2575);
PAINT MONO (13300 2575);
DISPLAY INVISIBLE (13300 2575);
FORCEADD Q_RES..2
(13300 2825);
FORCEPROP 1 LAST LOCATION R1605
J 0
(13345 2950);
DISPLAY 0.978723 (13345 2950);
FORCEPROP 2 LAST $SEC 1
J 0
(13350 3050);
DISPLAY 0.680851 (13350 3050);
PAINT MONO (13350 3050);
DISPLAY INVISIBLE (13350 3050);
FORCEPROP 2 LAST CDS_SEC 1
J 0
(13350 3050);
DISPLAY 1.021277 (13350 3050);
DISPLAY INVISIBLE (13350 3050);
FORCEPROP 1 LASTPIN (13300 2925) $PN 1
J 0
(13305 2887);
DISPLAY 0.787234 (13305 2887);
PAINT MONO (13305 2887);
FORCEPROP 1 LASTPIN (13300 2725) $PN 2
J 0
(13305 2735);
DISPLAY 0.787234 (13305 2735);
PAINT MONO (13305 2735);
FORCEPROP 1 LAST MATERIAL CHIP
J 0
(13340 2750);
DISPLAY 0.638298 (13340 2750);
FORCEPROP 1 LAST WATTAGE 1/16W
J 0
(13340 2800);
DISPLAY 0.638298 (13340 2800);
FORCEPROP 1 LAST TOLERANCE 1%
J 0
(13345 2850);
DISPLAY 0.638298 (13345 2850);
FORCEPROP 1 LAST VALUE 1K
J 0
(13345 2900);
DISPLAY 0.638298 (13345 2900);
FORCEPROP 1 LAST PACK_TYPE 0402LF
J 0
(13340 2650);
DISPLAY 0.638298 (13340 2650);
FORCEPROP 1 LAST PART_NUMBER CS21002FB06
J 0
(13340 2700);
DISPLAY 0.638298 (13340 2700);
DISPLAY INVISIBLE (13340 2700);
FORCEPROP 1 LAST PATH I83
J 0
(13350 3000);
DISPLAY 0.978723 (13350 3000);
PAINT WHITE (13350 3000);
DISPLAY INVISIBLE (13350 3000);
FORCEPROP 2 LAST CDS_LIB pure_quanta
J 0
(13300 2825);
PAINT MONO (13300 2825);
DISPLAY INVISIBLE (13300 2825);
FORCEADD Q_CAP..1
(12425 4200);
FORCEPROP 1 LAST LOCATION C1923
J 0
(12475 4300);
DISPLAY 0.978723 (12475 4300);
FORCEPROP 2 LAST $SEC 1
J 0
(12475 4400);
DISPLAY 0.680851 (12475 4400);
PAINT MONO (12475 4400);
DISPLAY INVISIBLE (12475 4400);
FORCEPROP 2 LAST CDS_SEC 1
J 0
(12475 4400);
DISPLAY 1.021277 (12475 4400);
DISPLAY INVISIBLE (12475 4400);
FORCEPROP 1 LASTPIN (12425 4300) $PN 1
J 0
(12435 4280);
DISPLAY 0.787234 (12435 4280);
FORCEPROP 1 LASTPIN (12425 4100) $PN 2
J 0
(12435 4080);
DISPLAY 0.787234 (12435 4080);
FORCEPROP 1 LAST VOLTAGE 25V
J 0
(12475 4200);
DISPLAY 0.638298 (12475 4200);
FORCEPROP 1 LAST VALUE 0.1UF
J 0
(12475 4250);
DISPLAY 0.638298 (12475 4250);
FORCEPROP 1 LAST MATERIAL X7R
J 0
(12475 4100);
DISPLAY 0.638298 (12475 4100);
FORCEPROP 1 LAST TOLERANCE 10%
J 0
(12475 4150);
DISPLAY 0.638298 (12475 4150);
FORCEPROP 1 LAST PACK_TYPE 0402
J 0
(12475 4000);
DISPLAY 0.638298 (12475 4000);
FORCEPROP 1 LAST PART_NUMBER CH4104K1B00
J 0
(12475 4050);
DISPLAY 0.638298 (12475 4050);
DISPLAY INVISIBLE (12475 4050);
FORCEPROP 1 LAST PATH I84
J 0
(12475 4350);
DISPLAY 0.978723 (12475 4350);
PAINT WHITE (12475 4350);
DISPLAY INVISIBLE (12475 4350);
FORCEPROP 2 LAST CDS_LIB pure_quanta
J 0
(12425 4200);
PAINT MONO (12425 4200);
DISPLAY INVISIBLE (12425 4200);
FORCEADD Q_CAP..1
(12825 4200);
FORCEPROP 1 LAST LOCATION C1924
J 0
(12875 4300);
DISPLAY 0.978723 (12875 4300);
FORCEPROP 2 LAST $SEC 1
J 0
(12875 4400);
DISPLAY 0.680851 (12875 4400);
PAINT MONO (12875 4400);
DISPLAY INVISIBLE (12875 4400);
FORCEPROP 2 LAST CDS_SEC 1
J 0
(12875 4400);
DISPLAY 1.021277 (12875 4400);
DISPLAY INVISIBLE (12875 4400);
FORCEPROP 1 LASTPIN (12825 4300) $PN 1
J 0
(12835 4280);
DISPLAY 0.787234 (12835 4280);
FORCEPROP 1 LASTPIN (12825 4100) $PN 2
J 0
(12835 4080);
DISPLAY 0.787234 (12835 4080);
FORCEPROP 1 LAST PACK_TYPE 0402
J 0
(12875 4000);
DISPLAY 0.638298 (12875 4000);
FORCEPROP 1 LAST VALUE 0.1UF
J 0
(12875 4250);
DISPLAY 0.638298 (12875 4250);
FORCEPROP 1 LAST MATERIAL X7R
J 0
(12875 4100);
DISPLAY 0.638298 (12875 4100);
FORCEPROP 1 LAST VOLTAGE 25V
J 0
(12875 4200);
DISPLAY 0.638298 (12875 4200);
FORCEPROP 1 LAST TOLERANCE 10%
J 0
(12875 4150);
DISPLAY 0.638298 (12875 4150);
FORCEPROP 1 LAST PART_NUMBER CH4104K1B00
J 0
(12875 4050);
DISPLAY 0.638298 (12875 4050);
DISPLAY INVISIBLE (12875 4050);
FORCEPROP 1 LAST PATH I85
J 0
(12875 4350);
DISPLAY 0.978723 (12875 4350);
PAINT WHITE (12875 4350);
DISPLAY INVISIBLE (12875 4350);
FORCEPROP 2 LAST CDS_LIB pure_quanta
J 0
(12825 4200);
PAINT MONO (12825 4200);
DISPLAY INVISIBLE (12825 4200);
FORCEADD Q_CAP..1
(13225 4200);
FORCEPROP 1 LAST LOCATION C1925
J 0
(13275 4300);
DISPLAY 0.978723 (13275 4300);
FORCEPROP 2 LAST $SEC 1
J 0
(13275 4400);
DISPLAY 0.680851 (13275 4400);
PAINT MONO (13275 4400);
DISPLAY INVISIBLE (13275 4400);
FORCEPROP 2 LAST CDS_SEC 1
J 0
(13275 4400);
DISPLAY 1.021277 (13275 4400);
DISPLAY INVISIBLE (13275 4400);
FORCEPROP 1 LASTPIN (13225 4300) $PN 1
J 0
(13235 4280);
DISPLAY 0.787234 (13235 4280);
FORCEPROP 1 LASTPIN (13225 4100) $PN 2
J 0
(13235 4080);
DISPLAY 0.787234 (13235 4080);
FORCEPROP 1 LAST TOLERANCE 10%
J 0
(13275 4150);
DISPLAY 0.638298 (13275 4150);
FORCEPROP 1 LAST VOLTAGE 25V
J 0
(13275 4200);
DISPLAY 0.638298 (13275 4200);
FORCEPROP 1 LAST PACK_TYPE 0402
J 0
(13275 4000);
DISPLAY 0.638298 (13275 4000);
FORCEPROP 1 LAST MATERIAL X7R
J 0
(13275 4100);
DISPLAY 0.638298 (13275 4100);
FORCEPROP 1 LAST VALUE 0.1UF
J 0
(13275 4250);
DISPLAY 0.638298 (13275 4250);
FORCEPROP 1 LAST PART_NUMBER CH4104K1B00
J 0
(13275 4050);
DISPLAY 0.638298 (13275 4050);
DISPLAY INVISIBLE (13275 4050);
FORCEPROP 1 LAST PATH I86
J 0
(13275 4350);
DISPLAY 0.978723 (13275 4350);
PAINT WHITE (13275 4350);
DISPLAY INVISIBLE (13275 4350);
FORCEPROP 2 LAST CDS_LIB pure_quanta
J 0
(13225 4200);
PAINT MONO (13225 4200);
DISPLAY INVISIBLE (13225 4200);
FORCEADD OFFPAGE..2
(12450 175);
FORCEPROP 2 LAST $XR0 144 
J 0
(12639 175);
DISPLAY 0.638298 (12639 175);
PAINT MONO (12639 175);
FORCEPROP 2 LAST PATH I87
J 0
(12650 225);
DISPLAY 0.680851 (12650 225);
DISPLAY INVISIBLE (12650 225);
FORCEPROP 1 LAST COMMENT_BODY TRUE
J 0
(12405 80);
DISPLAY 0.872340 (12405 80);
PAINT GREEN (12405 80);
DISPLAY INVISIBLE (12405 80);
FORCEPROP 1 LAST OFFPAGE TRUE
J 0
(12775 50);
DISPLAY 0.872340 (12775 50);
PAINT AQUA (12775 50);
DISPLAY INVISIBLE (12775 50);
FORCEPROP 2 LAST CDS_LIB standard
J 0
(12450 175);
DISPLAY INVISIBLE (12450 175);
FORCEADD SCONN75K_APCI0155P004A..1
R 2
(8675 3250);
FORCEPROP 1 LAST LOCATION J59
J 2
(9124 4563);
DISPLAY 0.723404 (9124 4563);
PAINT GREEN (9124 4563);
FORCEPROP 2 LAST $SEC 1
J 0
(8400 4775);
DISPLAY 0.680851 (8400 4775);
PAINT MONO (8400 4775);
DISPLAY INVISIBLE (8400 4775);
FORCEPROP 2 LAST CDS_SEC 1
J 0
(8500 4650);
DISPLAY 1.021277 (8500 4650);
DISPLAY INVISIBLE (8500 4650);
FORCEPROP 2 LASTPIN (9275 3925) $PN 2
J 0
(9285 3935);
DISPLAY 0.808511 (9285 3935);
FORCEPROP 2 LASTPIN (9275 3975) $PN 4
J 0
(9285 3985);
DISPLAY 0.808511 (9285 3985);
FORCEPROP 2 LASTPIN (9275 4025) $PN 12
J 0
(9285 4035);
DISPLAY 0.808511 (9285 4035);
FORCEPROP 2 LASTPIN (9275 4075) $PN 14
J 0
(9285 4085);
DISPLAY 0.808511 (9285 4085);
FORCEPROP 2 LASTPIN (9275 4125) $PN 16
J 0
(9285 4135);
DISPLAY 0.808511 (9285 4135);
FORCEPROP 2 LASTPIN (9275 4175) $PN 18
J 0
(9285 4185);
DISPLAY 0.808511 (9285 4185);
FORCEPROP 2 LASTPIN (9275 4225) $PN 70
J 0
(9285 4235);
DISPLAY 0.808511 (9285 4235);
FORCEPROP 2 LASTPIN (9275 4275) $PN 72
J 0
(9285 4285);
DISPLAY 0.808511 (9285 4285);
FORCEPROP 2 LASTPIN (9275 4325) $PN 74
J 0
(9285 4335);
DISPLAY 0.808511 (9285 4335);
FORCEPROP 2 LASTPIN (8075 3275) $PN 52
J 2
(8065 3285);
DISPLAY 0.808511 (8065 3285);
FORCEPROP 2 LASTPIN (9275 3525) $PN 10
J 0
(9285 3535);
DISPLAY 0.808511 (9285 3535);
FORCEPROP 2 LASTPIN (8075 3475) $PN 38
J 2
(8065 3485);
DISPLAY 0.808511 (8065 3485);
FORCEPROP 2 LASTPIN (8075 2225) $PN G1
J 2
(8065 2235);
DISPLAY 0.808511 (8065 2235);
FORCEPROP 2 LASTPIN (8075 2175) $PN G2
J 2
(8065 2185);
DISPLAY 0.808511 (8065 2185);
FORCEPROP 2 LASTPIN (8075 2325) $PN 1
J 2
(8065 2335);
DISPLAY 0.808511 (8065 2335);
FORCEPROP 2 LASTPIN (8075 2375) $PN 3
J 2
(8065 2385);
DISPLAY 0.808511 (8065 2385);
FORCEPROP 2 LASTPIN (8075 2425) $PN 9
J 2
(8065 2435);
DISPLAY 0.808511 (8065 2435);
FORCEPROP 2 LASTPIN (8075 2475) $PN 15
J 2
(8065 2485);
DISPLAY 0.808511 (8065 2485);
FORCEPROP 2 LASTPIN (8075 2525) $PN 21
J 2
(8065 2535);
DISPLAY 0.808511 (8065 2535);
FORCEPROP 2 LASTPIN (8075 2575) $PN 27
J 2
(8065 2585);
DISPLAY 0.808511 (8065 2585);
FORCEPROP 2 LASTPIN (8075 2625) $PN 33
J 2
(8065 2635);
DISPLAY 0.808511 (8065 2635);
FORCEPROP 2 LASTPIN (8075 2675) $PN 39
J 2
(8065 2685);
DISPLAY 0.808511 (8065 2685);
FORCEPROP 2 LASTPIN (8075 2725) $PN 45
J 2
(8065 2735);
DISPLAY 0.808511 (8065 2735);
FORCEPROP 2 LASTPIN (8075 2775) $PN 51
J 2
(8065 2785);
DISPLAY 0.808511 (8065 2785);
FORCEPROP 2 LASTPIN (8075 2825) $PN 57
J 2
(8065 2835);
DISPLAY 0.808511 (8065 2835);
FORCEPROP 2 LASTPIN (8075 2875) $PN 71
J 2
(8065 2885);
DISPLAY 0.808511 (8065 2885);
FORCEPROP 2 LASTPIN (8075 2925) $PN 73
J 2
(8065 2935);
DISPLAY 0.808511 (8065 2935);
FORCEPROP 2 LASTPIN (8075 2975) $PN 75
J 2
(8065 2985);
DISPLAY 0.808511 (8065 2985);
FORCEPROP 2 LASTPIN (9275 2375) $PN 6
J 0
(9285 2385);
DISPLAY 0.808511 (9285 2385);
FORCEPROP 2 LASTPIN (9275 2425) $PN 8
J 0
(9285 2435);
DISPLAY 0.808511 (9285 2435);
FORCEPROP 2 LASTPIN (9275 2475) $PN 20
J 0
(9285 2485);
DISPLAY 0.808511 (9285 2485);
FORCEPROP 2 LASTPIN (9275 2525) $PN 22
J 0
(9285 2535);
DISPLAY 0.808511 (9285 2535);
FORCEPROP 2 LASTPIN (9275 2575) $PN 24
J 0
(9285 2585);
DISPLAY 0.808511 (9285 2585);
FORCEPROP 2 LASTPIN (9275 2625) $PN 26
J 0
(9285 2635);
DISPLAY 0.808511 (9285 2635);
FORCEPROP 2 LASTPIN (9275 2675) $PN 28
J 0
(9285 2685);
DISPLAY 0.808511 (9285 2685);
FORCEPROP 2 LASTPIN (9275 2725) $PN 30
J 0
(9285 2735);
DISPLAY 0.808511 (9285 2735);
FORCEPROP 2 LASTPIN (9275 2775) $PN 32
J 0
(9285 2785);
DISPLAY 0.808511 (9285 2785);
FORCEPROP 2 LASTPIN (9275 2825) $PN 34
J 0
(9285 2835);
DISPLAY 0.808511 (9285 2835);
FORCEPROP 2 LASTPIN (9275 2875) $PN 36
J 0
(9285 2885);
DISPLAY 0.808511 (9285 2885);
FORCEPROP 2 LASTPIN (9275 2925) $PN 40
J 0
(9285 2935);
DISPLAY 0.808511 (9285 2935);
FORCEPROP 2 LASTPIN (9275 2975) $PN 42
J 0
(9285 2985);
DISPLAY 0.808511 (9285 2985);
FORCEPROP 2 LASTPIN (9275 3025) $PN 44
J 0
(9285 3035);
DISPLAY 0.808511 (9285 3035);
FORCEPROP 2 LASTPIN (9275 3075) $PN 46
J 0
(9285 3085);
DISPLAY 0.808511 (9285 3085);
FORCEPROP 2 LASTPIN (9275 3125) $PN 48
J 0
(9285 3135);
DISPLAY 0.808511 (9285 3135);
FORCEPROP 2 LASTPIN (9275 3175) $PN 56
J 0
(9285 3185);
DISPLAY 0.808511 (9285 3185);
FORCEPROP 2 LASTPIN (9275 3225) $PN 58
J 0
(9285 3235);
DISPLAY 0.808511 (9285 3235);
FORCEPROP 2 LASTPIN (9275 3275) $PN 67
J 0
(9285 3285);
DISPLAY 0.808511 (9285 3285);
FORCEPROP 2 LASTPIN (9275 3425) $PN 69
J 0
(9285 3435);
DISPLAY 0.808511 (9285 3435);
FORCEPROP 2 LASTPIN (9275 3775) $PN 41
J 0
(9285 3785);
DISPLAY 0.808511 (9285 3785);
FORCEPROP 2 LASTPIN (8075 3775) $PN 29
J 2
(8065 3785);
DISPLAY 0.808511 (8065 3785);
FORCEPROP 2 LASTPIN (8075 4025) $PN 17
J 2
(8065 4035);
DISPLAY 0.808511 (8065 4035);
FORCEPROP 2 LASTPIN (8075 4275) $PN 5
J 2
(8065 4285);
DISPLAY 0.808511 (8065 4285);
FORCEPROP 2 LASTPIN (9275 3825) $PN 43
J 0
(9285 3835);
DISPLAY 0.808511 (9285 3835);
FORCEPROP 2 LASTPIN (8075 3825) $PN 31
J 2
(8065 3835);
DISPLAY 0.808511 (8065 3835);
FORCEPROP 2 LASTPIN (8075 4075) $PN 19
J 2
(8065 4085);
DISPLAY 0.808511 (8065 4085);
FORCEPROP 2 LASTPIN (8075 4325) $PN 7
J 2
(8065 4335);
DISPLAY 0.808511 (8065 4335);
FORCEPROP 2 LASTPIN (8075 3375) $PN 50
J 2
(8065 3385);
DISPLAY 0.808511 (8065 3385);
FORCEPROP 2 LASTPIN (9275 3625) $PN 47
J 0
(9285 3635);
DISPLAY 0.808511 (9285 3635);
FORCEPROP 2 LASTPIN (8075 3675) $PN 35
J 2
(8065 3685);
DISPLAY 0.808511 (8065 3685);
FORCEPROP 2 LASTPIN (8075 3925) $PN 23
J 2
(8065 3935);
DISPLAY 0.808511 (8065 3935);
FORCEPROP 2 LASTPIN (8075 4175) $PN 11
J 2
(8065 4185);
DISPLAY 0.808511 (8065 4185);
FORCEPROP 2 LASTPIN (9275 3675) $PN 49
J 0
(9285 3685);
DISPLAY 0.808511 (9285 3685);
FORCEPROP 2 LASTPIN (8075 3725) $PN 37
J 2
(8065 3735);
DISPLAY 0.808511 (8065 3735);
FORCEPROP 2 LASTPIN (8075 3975) $PN 25
J 2
(8065 3985);
DISPLAY 0.808511 (8065 3985);
FORCEPROP 2 LASTPIN (8075 4225) $PN 13
J 2
(8065 4235);
DISPLAY 0.808511 (8065 4235);
FORCEPROP 2 LASTPIN (8075 3225) $PN 54
J 2
(8065 3235);
DISPLAY 0.808511 (8065 3235);
FORCEPROP 2 LASTPIN (8075 3075) $PN 53
J 2
(8065 3085);
DISPLAY 0.808511 (8065 3085);
FORCEPROP 2 LASTPIN (8075 3125) $PN 55
J 2
(8065 3135);
DISPLAY 0.808511 (8065 3135);
FORCEPROP 2 LASTPIN (8075 3575) $PN 68
J 2
(8065 3585);
DISPLAY 0.808511 (8065 3585);
FORCEPROP 2 LAST VALUE SCONN75K_APCI0155-P004A
J 2
(8975 4675);
DISPLAY 0.638298 (8975 4675);
FORCEPROP 2 LAST PART_TYPE SMLF
J 2
(8400 4725);
DISPLAY 0.638298 (8400 4725);
FORCEPROP 1 LAST MATERIAL EMPTY
J 2
(9125 4400);
DISPLAY 1.148936 (9125 4400);
PAINT RED (9125 4400);
FORCEPROP 1 LAST PART_NUMBER DFHS75FR313
J 2
(9124 4479);
DISPLAY 0.723404 (9124 4479);
PAINT GREEN (9124 4479);
DISPLAY INVISIBLE (9124 4479);
FORCEPROP 1 LAST PATH I88
J 2
(8225 2125);
DISPLAY 0.723404 (8225 2125);
PAINT GREEN (8225 2125);
DISPLAY INVISIBLE (8225 2125);
FORCEPROP 2 LAST CDS_LIB pure_quanta
J 0
(8675 3250);
PAINT MONO (8675 3250);
DISPLAY INVISIBLE (8675 3250);
FORCEPROP 1 LAST CDS_LMAN_SYM_OUTLINE -450,1125,450,-1125
J 2
(8675 3250);
DISPLAY 0.468085 (8675 3250);
PAINT GREEN (8675 3250);
DISPLAY INVISIBLE (8675 3250);
FORCEPROP 1 LAST PIN_NAMES_ROTATE True
J 2
(8675 3250);
DISPLAY 0.489362 (8675 3250);
PAINT GREEN (8675 3250);
DISPLAY INVISIBLE (8675 3250);
FORCEADD MOSFET_NCH_DUAL..2
(10400 -800);
FORCEPROP 1 LAST LOCATION Q95
J 0
(10551 -824);
DISPLAY 0.723404 (10551 -824);
PAINT GREEN (10551 -824);
FORCEPROP 0 LAST $SEC 2
J 0
(10575 -675);
DISPLAY 0.680851 (10575 -675);
PAINT MONO (10575 -675);
DISPLAY INVISIBLE (10575 -675);
FORCEPROP 0 LAST CDS_SEC 2
J 0
(10575 -675);
DISPLAY 0.680851 (10575 -675);
DISPLAY INVISIBLE (10575 -675);
FORCEPROP 0 LASTPIN (10450 -600) $PN 3
R 1
J 0
(10440 -590);
DISPLAY 0.680851 (10440 -590);
PAINT MONO (10440 -590);
FORCEPROP 0 LASTPIN (10200 -850) $PN 5
J 2
(10190 -840);
DISPLAY 0.680851 (10190 -840);
PAINT MONO (10190 -840);
FORCEPROP 0 LASTPIN (10450 -1000) $PN 4
R 1
J 2
(10440 -1010);
DISPLAY 0.680851 (10440 -1010);
PAINT MONO (10440 -1010);
FORCEPROP 1 LAST MATERIAL IC
J 0
(10551 -949);
DISPLAY 0.723404 (10551 -949);
PAINT GREEN (10551 -949);
FORCEPROP 2 LAST PART_TYPE SMLF
J 0
(10575 -725);
DISPLAY 0.680851 (10575 -725);
FORCEPROP 2 LAST VALUE PJT138K
J 0
(10575 -775);
DISPLAY 0.680851 (10575 -775);
FORCEPROP 1 LAST PART_NUMBER BAM138K0003
J 0
(10551 -894);
DISPLAY 0.723404 (10551 -894);
PAINT GREEN (10551 -894);
DISPLAY INVISIBLE (10551 -894);
FORCEPROP 1 LAST PATH I89
J 0
(10550 -950);
DISPLAY 0.723404 (10550 -950);
PAINT GREEN (10550 -950);
DISPLAY INVISIBLE (10550 -950);
FORCEPROP 1 LAST CDS_LMAN_SYM_OUTLINE -150,150,150,-150
J 0
(10400 -800);
DISPLAY 0.468085 (10400 -800);
PAINT GREEN (10400 -800);
DISPLAY INVISIBLE (10400 -800);
FORCEPROP 1 LAST NEEDS_NO_SIZE TRUE
J 0
(10550 -909);
DISPLAY 0.468085 (10550 -909);
PAINT GREEN (10550 -909);
DISPLAY INVISIBLE (10550 -909);
FORCEPROP 2 LAST CDS_LIB pure_quanta
J 0
(10400 -800);
DISPLAY INVISIBLE (10400 -800);
FORCEADD UNIVERSAL_GND..1
(9800 -475);
FORCEPROP 3 LASTPIN (9800 -425) SIG_NAME GND\g
J 0
(9810 -415);
DISPLAY 0.659574 (9810 -415);
PAINT MONO (9810 -415);
DISPLAY INVISIBLE (9810 -415);
FORCEPROP 1 LAST PATH I9
J 0
(9875 -475);
DISPLAY 0.872340 (9875 -475);
PAINT AQUA (9875 -475);
DISPLAY INVISIBLE (9875 -475);
FORCEPROP 1 LAST HDL_POWER GND
J 1
(9825 -550);
DISPLAY 0.872340 (9825 -550);
PAINT GREEN (9825 -550);
DISPLAY INVISIBLE (9825 -550);
FORCEPROP 2 LAST CDS_LIB pure_quanta_power
J 0
(9800 -475);
DISPLAY INVISIBLE (9800 -475);
FORCEADD DNS..2
(5405 2995);
PAINT RED (5405 2995);
FORCEPROP 1 LAST COMMENT_BODY TRUE
J 0
(5405 2995);
DISPLAY INVISIBLE (5405 2995);
FORCEPROP 2 LAST CDS_LIB mstr_misc
J 0
(5405 2995);
PAINT MONO (5405 2995);
DISPLAY INVISIBLE (5405 2995);
FORCEADD DNS..2
(6825 3875);
PAINT RED (6825 3875);
FORCEPROP 1 LAST COMMENT_BODY TRUE
J 0
(6825 3875);
DISPLAY INVISIBLE (6825 3875);
FORCEPROP 2 LAST CDS_LIB mstr_misc
J 0
(6825 3875);
DISPLAY INVISIBLE (6825 3875);
FORCEADD QUANTA_TITLE_BLOCK_C..1
(13950 -1375);
FORCEPROP 0 LAST CDS_CON_LAST_MODIFIED Thu Sep 14 16:12:27 2023
J 0
(12065 -1360);
PAINT MONO (12065 -1360);
DISPLAY INVISIBLE (12065 -1360);
FORCEPROP 2 LAST CUSTOM_TXT_CDS <XR_PAGE_TITLE>
J 0
(6060 3875);
DISPLAY 0.638298 (6060 3875);
PAINT PINK (6060 3875);
DISPLAY INVISIBLE (6060 3875);
FORCEPROP 2 LAST CUSTOM_TXT_CDS <CON_LAST_MODIFIED>
J 0
(12065 -1360);
DISPLAY 0.978723 (12065 -1360);
FORCEPROP 2 LAST CUSTOM_TXT_CDS <Q_PROJ>
J 0
(11568 -1273);
DISPLAY 1.212766 (11568 -1273);
FORCEPROP 2 LAST CUSTOM_TXT_CDS <Q_NUMBER>
J 0
(12547 -1272);
DISPLAY 1.212766 (12547 -1272);
FORCEPROP 2 LAST CUSTOM_TXT_CDS <NAME_2>
J 0
(10775 -1325);
FORCEPROP 2 LAST CUSTOM_TXT_CDS <Q_REV>
J 0
(13766 -1272);
DISPLAY 1.212766 (13766 -1272);
FORCEPROP 2 LAST CUSTOM_TXT_CDS 01
J 0
(13766 -1272);
DISPLAY 1.212766 (13766 -1272);
FORCEPROP 2 LAST CUSTOM_TXT_CDS 01
J 0
(13766 -1272);
DISPLAY 1.212766 (13766 -1272);
FORCEPROP 2 LAST CUSTOM_TXT_CDS 01
J 0
(13766 -1272);
DISPLAY 1.212766 (13766 -1272);
FORCEPROP 2 LAST CUSTOM_TXT_CDS 01
J 0
(13766 -1272);
DISPLAY 1.212766 (13766 -1272);
FORCEPROP 2 LAST CUSTOM_TXT_CDS <CON_PAGE_NUM> OF <CON_TOTAL_PAGES>
J 0
(13504 -1357);
DISPLAY 0.978723 (13504 -1357);
FORCEPROP 2 LAST CUSTOM_TXT_CDS <NAME_1>
J 0
(10775 -1200);
FORCEPROP 1 LAST Q_TITLE CPU1 - M.2 - 0 CONN (EMPTY)
J 0
(4609 -1349);
DISPLAY 1.957447 (4609 -1349);
PAINT GREEN (4609 -1349);
FORCEPROP 1 LAST COMMENT_BODY TRUE
J 0
(13962 -1388);
DISPLAY 0.978723 (13962 -1388);
PAINT GREEN (13962 -1388);
DISPLAY INVISIBLE (13962 -1388);
FORCEPROP 1 LAST Q_DEPT BU9
J 1
(10187 -1326);
DISPLAY 1.957447 (10187 -1326);
PAINT GREEN (10187 -1326);
DISPLAY INVISIBLE (10187 -1326);
FORCEPROP 2 LAST CDS_XR_PAGE_TITLE CR-144 : @T6G_MB_LIB.T6G(SCH_1):PAGE144
J 0
(6060 3875);
DISPLAY 0.638298 (6060 3875);
PAINT PINK (6060 3875);
DISPLAY INVISIBLE (6060 3875);
FORCEPROP 2 LAST PAGE_BORDER TRUE
J 0
(6060 3875);
DISPLAY 0.638298 (6060 3875);
PAINT PINK (6060 3875);
DISPLAY INVISIBLE (6060 3875);
FORCEPROP 1 LAST CDS_LMAN_SYM_OUTLINE -9475,6775,100,-125
J 0
(13950 -1375);
DISPLAY 0.468085 (13950 -1375);
PAINT GREEN (13950 -1375);
DISPLAY INVISIBLE (13950 -1375);
FORCEPROP 2 LAST CDS_LIB pure_quanta
J 0
(13950 -1375);
PAINT MONO (13950 -1375);
DISPLAY INVISIBLE (13950 -1375);
FORCEADD DNS..2
(9050 4575);
PAINT RED (9050 4575);
FORCEPROP 1 LAST COMMENT_BODY TRUE
J 0
(9050 4575);
DISPLAY INVISIBLE (9050 4575);
FORCEPROP 2 LAST CDS_LIB mstr_misc
J 0
(9050 4575);
DISPLAY INVISIBLE (9050 4575);
WIRE 17 -1 (7625 3950)(7625 4200);
WIRE 17 -1 (7625 3950)(7625 3700);
WIRE 17 -1 (7625 4200)(7625 4550);
WIRE 17 -1 (6125 4550)(7625 4550);
FORCEPROP 2 LAST SIG_NAME P3E_CPU1_P4_TX_C_DN<3:1>
J 0
(6315 4560);
DISPLAY 0.680851 (6315 4560);
PAINT WHITE (6315 4560);
WIRE 17 -1 (7300 3850)(7300 4100);
WIRE 17 -1 (7300 4100)(7300 4350);
WIRE 17 -1 (7300 4450)(7300 4350);
WIRE 17 -1 (6125 4450)(7300 4450);
FORCEPROP 2 LAST SIG_NAME P3E_CPU1_P4_RX_DP<3:1>
J 0
(6315 4460);
DISPLAY 0.680851 (6315 4460);
PAINT WHITE (6315 4460);
WIRE 17 -1 (7150 4050)(7150 3800);
WIRE 17 -1 (7150 4300)(7150 4050);
WIRE 17 -1 (7150 4300)(7150 4400);
WIRE 17 -1 (7150 4400)(6125 4400);
FORCEPROP 2 LAST SIG_NAME P3E_CPU1_P4_RX_DN<3:1>
J 0
(6315 4410);
DISPLAY 0.680851 (6315 4410);
PAINT WHITE (6315 4410);
WIRE 17 -1 (7475 3750)(7475 4000);
WIRE 17 -1 (7475 4250)(7475 4000);
WIRE 17 -1 (7475 4250)(7475 4500);
WIRE 17 -1 (7475 4500)(6125 4500);
FORCEPROP 2 LAST SIG_NAME P3E_CPU1_P4_TX_C_DP<3:1>
J 0
(6315 4510);
DISPLAY 0.680851 (6315 4510);
PAINT WHITE (6315 4510);
WIRE 16 -1 (10675 -225)(10675 -150);
WIRE 16 -1 (5400 2825)(5400 2900);
WIRE 16 -1 (7600 1550)(7600 1650);
WIRE 16 -1 (6925 2725)(6925 2800);
WIRE 16 -1 (8000 -1075)(8000 -925);
WIRE 16 -1 (6925 3950)(6925 4025);
WIRE 16 -1 (8575 325)(8575 500);
WIRE 16 -1 (9300 850)(9300 750);
WIRE 16 -1 (9550 1250)(9550 1350);
WIRE 16 -1 (10250 750)(10250 650);
WIRE 16 -1 (10675 575)(10675 525);
WIRE 16 -1 (7950 -475)(8000 -475);
WIRE 16 -1 (8000 -475)(8000 -325);
WIRE 16 -1 (8000 -725)(8000 -475);
WIRE 16 -1 (10650 3200)(11125 3200);
WIRE 16 -1 (11125 3200)(11125 3225);
WIRE 16 -1 (13300 2625)(13300 2725);
WIRE 16 -1 (9800 -325)(9800 -425);
WIRE 16 -1 (7925 2975)(8075 2975);
WIRE 16 -1 (7925 2925)(7925 2975);
WIRE 16 -1 (7925 2925)(8075 2925);
WIRE 16 -1 (7925 2875)(7925 2925);
WIRE 16 -1 (7925 2875)(8075 2875);
WIRE 16 -1 (7925 2825)(7925 2875);
WIRE 16 -1 (7925 2825)(8075 2825);
WIRE 16 -1 (7925 2775)(7925 2825);
WIRE 16 -1 (7925 2775)(8075 2775);
WIRE 16 -1 (7925 2725)(7925 2775);
WIRE 16 -1 (7925 2725)(8075 2725);
WIRE 16 -1 (7925 2725)(7925 2675);
WIRE 16 -1 (7925 2675)(8075 2675);
WIRE 16 -1 (7925 2675)(7925 2625);
WIRE 16 -1 (7925 2625)(8075 2625);
WIRE 16 -1 (7925 2625)(7925 2575);
WIRE 16 -1 (7925 2575)(8075 2575);
WIRE 16 -1 (7925 2575)(7925 2525);
WIRE 16 -1 (7925 2525)(8075 2525);
WIRE 16 -1 (7925 2525)(7925 2475);
WIRE 16 -1 (7925 2475)(8075 2475);
WIRE 16 -1 (7925 2475)(7925 2425);
WIRE 16 -1 (7925 2425)(8075 2425);
WIRE 16 -1 (7925 2425)(7925 2375);
WIRE 16 -1 (7925 2375)(8075 2375);
WIRE 16 -1 (7925 2225)(7925 2375);
WIRE 16 -1 (7925 2225)(8075 2225);
WIRE 16 -1 (7925 2225)(7925 2175);
WIRE 16 -1 (7925 2175)(8075 2175);
WIRE 16 -1 (7925 2175)(7925 2075);
WIRE 16 -1 (7200 -475)(7300 -475);
WIRE 16 -1 (7200 -625)(7200 -475);
WIRE 16 -1 (9550 1650)(9550 1550);
WIRE 16 -1 (9300 1650)(9550 1650);
WIRE 16 -1 (9300 1350)(9300 1650);
WIRE 16 -1 (9300 1650)(9300 1750);
WIRE 16 -1 (9275 3925)(9425 3925);
WIRE 16 -1 (9425 3975)(9425 3925);
WIRE 16 -1 (9425 4025)(9425 3975);
WIRE 16 -1 (9275 3975)(9425 3975);
WIRE 16 -1 (9425 4075)(9425 4025);
WIRE 16 -1 (9275 4025)(9425 4025);
WIRE 16 -1 (9425 4125)(9425 4075);
WIRE 16 -1 (9275 4075)(9425 4075);
WIRE 16 -1 (9425 4175)(9425 4125);
WIRE 16 -1 (9275 4125)(9425 4125);
WIRE 16 -1 (9425 4225)(9425 4175);
WIRE 16 -1 (9275 4175)(9425 4175);
WIRE 16 -1 (9425 4275)(9425 4225);
WIRE 16 -1 (9275 4225)(9425 4225);
WIRE 16 -1 (9425 4325)(9425 4275);
WIRE 16 -1 (9275 4275)(9425 4275);
WIRE 16 -1 (9425 4525)(9425 4325);
WIRE 16 -1 (9275 4325)(9425 4325);
WIRE 16 -1 (13225 4400)(13225 4300);
WIRE 16 -1 (12825 4400)(13225 4400);
WIRE 16 -1 (12825 4400)(12825 4300);
WIRE 16 -1 (12425 4400)(12825 4400);
WIRE 16 -1 (12425 4400)(12425 4300);
WIRE 16 -1 (12025 4400)(12425 4400);
WIRE 16 -1 (12025 4300)(12025 4400);
WIRE 16 -1 (11625 4400)(12025 4400);
WIRE 16 -1 (11625 4300)(11625 4400);
WIRE 16 -1 (11225 4400)(11625 4400);
WIRE 16 -1 (11225 4525)(11225 4400);
WIRE 16 -1 (11225 4300)(11225 4400);
WIRE 16 -1 (11225 4100)(11225 3950);
WIRE 16 -1 (11225 3950)(11625 3950);
WIRE 16 -1 (11625 4100)(11625 3950);
WIRE 16 -1 (11625 3950)(12025 3950);
WIRE 16 -1 (12025 3950)(12425 3950);
WIRE 16 -1 (12025 4100)(12025 3950);
WIRE 16 -1 (12425 4100)(12425 3950);
WIRE 16 -1 (12425 3950)(12825 3950);
WIRE 16 -1 (12825 4100)(12825 3950);
WIRE 16 -1 (12825 3950)(13225 3950);
WIRE 16 -1 (13225 4100)(13225 3950);
WIRE 16 -1 (13225 3950)(13225 3900);
WIRE 16 -1 (9275 2625)(10075 2625);
FORCEPROP 2 LAST SIG_NAME NC_M2_0_NC6
J 0
(9465 2635);
DISPLAY 0.680851 (9465 2635);
PAINT WHITE (9465 2635);
FORCEPROP 2 LASTPROP $XRERR UNIQUE?
J 0
(10105 2625);
DISPLAY 0.638298 (10105 2625);
PAINT MONO (10105 2625);
DISPLAY INVISIBLE (10105 2625);
WIRE 16 -1 (9275 2575)(10075 2575);
FORCEPROP 2 LAST SIG_NAME NC_M2_0_NC5
J 0
(9465 2585);
DISPLAY 0.680851 (9465 2585);
PAINT WHITE (9465 2585);
FORCEPROP 2 LASTPROP $XRERR UNIQUE?
J 0
(10105 2575);
DISPLAY 0.638298 (10105 2575);
PAINT MONO (10105 2575);
DISPLAY INVISIBLE (10105 2575);
WIRE 16 -1 (9275 2525)(10075 2525);
FORCEPROP 2 LAST SIG_NAME NC_M2_0_NC4
J 0
(9465 2535);
DISPLAY 0.680851 (9465 2535);
PAINT WHITE (9465 2535);
FORCEPROP 2 LASTPROP $XRERR UNIQUE?
J 0
(10105 2525);
DISPLAY 0.638298 (10105 2525);
PAINT MONO (10105 2525);
DISPLAY INVISIBLE (10105 2525);
WIRE 16 -1 (9275 2475)(10075 2475);
FORCEPROP 2 LAST SIG_NAME NC_M2_0_NC3
J 0
(9465 2485);
DISPLAY 0.680851 (9465 2485);
PAINT WHITE (9465 2485);
FORCEPROP 2 LASTPROP $XRERR UNIQUE?
J 0
(10105 2475);
DISPLAY 0.638298 (10105 2475);
PAINT MONO (10105 2475);
DISPLAY INVISIBLE (10105 2475);
WIRE 16 -1 (9275 2425)(10075 2425);
FORCEPROP 2 LAST SIG_NAME NC_M2_0_NC2
J 0
(9465 2435);
DISPLAY 0.680851 (9465 2435);
PAINT WHITE (9465 2435);
FORCEPROP 2 LASTPROP $XRERR UNIQUE?
J 0
(10105 2425);
DISPLAY 0.638298 (10105 2425);
PAINT MONO (10105 2425);
DISPLAY INVISIBLE (10105 2425);
WIRE 16 -1 (9275 2375)(10075 2375);
FORCEPROP 2 LAST SIG_NAME NC_M2_0_NC1
J 0
(9465 2385);
DISPLAY 0.680851 (9465 2385);
PAINT WHITE (9465 2385);
FORCEPROP 2 LASTPROP $XRERR UNIQUE?
J 0
(10105 2375);
DISPLAY 0.638298 (10105 2375);
PAINT MONO (10105 2375);
DISPLAY INVISIBLE (10105 2375);
WIRE 16 -1 (7950 -425)(8575 -425);
WIRE 16 -1 (8575 -425)(8575 -175);
WIRE 16 -1 (8575 125)(8575 -175);
WIRE 16 -1 (8575 -175)(9550 -175);
FORCEPROP 2 LAST SIG_NAME HDD_ACTIVITY_BUF
J 0
(8640 -175);
DISPLAY 0.808511 (8640 -175);
PAINT WHITE (8640 -175);
FORCEPROP 2 LASTPROP $XRERR UNIQUE?
J 0
(8400 -175);
DISPLAY 0.638298 (8400 -175);
PAINT MONO (8400 -175);
DISPLAY INVISIBLE (8400 -175);
WIRE 16 -1 (9800 75)(9800 175);
WIRE 16 -1 (10675 175)(9800 175);
FORCEPROP 2 LAST SIG_NAME HDD_ACTIVITY_BUF_N
J 0
(9865 185);
DISPLAY 0.808511 (9865 185);
PAINT WHITE (9865 185);
FORCEPROP 2 LASTPROP $XRERR UNIQUE?
J 0
(9625 185);
DISPLAY 0.638298 (9625 185);
PAINT MONO (9625 185);
DISPLAY INVISIBLE (9625 185);
WIRE 16 -1 (10675 175)(10850 175);
WIRE 16 -1 (10675 325)(10675 175);
WIRE 16 -1 (11050 175)(12400 175);
FORCEPROP 2 LAST SIG_NAME PU_BUFFER_HDD_ACTIVITY
J 0
(11465 185);
DISPLAY 0.808511 (11465 185);
PAINT WHITE (11465 185);
WIRE 16 -1 (12500 3075)(13300 3075);
FORCEPROP 2 LAST SIG_NAME PD_M2_0_DEVSLP
J 0
(12690 3085);
DISPLAY 0.680851 (12690 3085);
PAINT WHITE (12690 3085);
WIRE 16 -1 (13300 3075)(13300 2925);
WIRE 16 -1 (9550 1100)(10250 1100);
WIRE 16 -1 (10250 1100)(11400 1100);
FORCEPROP 2 LAST SIG_NAME LED_HDD_ACTIVITY_B_N
J 0
(10540 1125);
DISPLAY 0.808511 (10540 1125);
PAINT WHITE (10540 1125);
WIRE 16 -1 (10250 950)(10250 1100);
WIRE 16 -1 (7125 1150)(7600 1150);
WIRE 16 -1 (9050 1150)(7600 1150);
FORCEPROP 2 LAST SIG_NAME LED_HDD_ACTIVITY_N
J 0
(8190 1160);
DISPLAY 0.723404 (8190 1160);
PAINT WHITE (8190 1160);
FORCEPROP 2 LASTPROP $XRERR UNIQUE?
J 0
(7950 1160);
DISPLAY 0.638298 (7950 1160);
PAINT MONO (7950 1160);
DISPLAY INVISIBLE (7950 1160);
WIRE 16 -1 (7600 1350)(7600 1150);
WIRE 16 -1 (7575 4225)(8075 4225);
WIRE 16 -1 (8075 4275)(7250 4275);
WIRE 16 -1 (7400 4325)(8075 4325);
WIRE 16 -1 (7400 4075)(8075 4075);
WIRE 16 -1 (8075 4025)(7250 4025);
WIRE 16 -1 (7575 3975)(8075 3975);
WIRE 16 -1 (6175 3225)(6825 3225);
FORCEPROP 0 LAST CDS_PHYS_NET_NAME IRQ_LVC3_WAKE_N
J 0
(6665 3261);
PAINT MONO (6665 3261);
DISPLAY INVISIBLE (6665 3261);
FORCEPROP 2 LAST SIG_NAME M2_0_PEWAKE_R_N
J 0
(6240 3235);
DISPLAY 0.553191 (6240 3235);
PAINT WHITE (6240 3235);
WIRE 16 -1 (8075 3375)(6475 3375);
FORCEPROP 0 LAST CDS_PHYS_NET_NAME RST_PCIE_PCH_DEV_0_N
J 0
(6665 3417);
PAINT MONO (6665 3417);
DISPLAY INVISIBLE (6665 3417);
FORCEPROP 2 LAST SIG_NAME RST_PERST_BUF_M2_0_R_N
J 0
(7165 3385);
DISPLAY 0.680851 (7165 3385);
PAINT WHITE (7165 3385);
WIRE 16 -1 (8075 3475)(6875 3475);
FORCEPROP 0 LAST CDS_PHYS_NET_NAME PD_M2_0_DEVSLP
J 0
(7215 3517);
PAINT MONO (7215 3517);
DISPLAY INVISIBLE (7215 3517);
FORCEPROP 2 LAST SIG_NAME PD_M2_0_DEVSLP
J 0
(7165 3485);
DISPLAY 0.680851 (7165 3485);
PAINT WHITE (7165 3485);
WIRE 16 -1 (7025 3575)(8075 3575);
FORCEPROP 0 LAST CDS_PHYS_NET_NAME NC_M2_0_SUSCLK
J 0
(7215 3617);
PAINT MONO (7215 3617);
DISPLAY INVISIBLE (7215 3617);
FORCEPROP 2 LAST SIG_NAME NC_M2_0_SUSCLK
J 0
(7165 3585);
DISPLAY 0.680851 (7165 3585);
PAINT WHITE (7165 3585);
FORCEPROP 2 LASTPROP $XRERR UNIQUE?
J 0
(6785 3575);
DISPLAY 0.638298 (6785 3575);
PAINT MONO (6785 3575);
DISPLAY INVISIBLE (6785 3575);
WIRE 16 -1 (10200 -850)(9975 -850);
FORCEPROP 2 LAST SIG_NAME NC_Q95_G2
J 0
(9905 -840);
DISPLAY 0.510638 (9905 -840);
PAINT WHITE (9905 -840);
FORCEPROP 2 LASTPROP $XRERR UNIQUE?
J 0
(9735 -850);
DISPLAY 0.638298 (9735 -850);
PAINT MONO (9735 -850);
DISPLAY INVISIBLE (9735 -850);
WIRE 16 -1 (10450 -1075)(10450 -1000);
WIRE 16 -1 (9975 -1075)(10450 -1075);
FORCEPROP 2 LAST SIG_NAME NC_Q95_S2
J 0
(10015 -1065);
DISPLAY 0.510638 (10015 -1065);
PAINT WHITE (10015 -1065);
FORCEPROP 2 LASTPROP $XRERR UNIQUE?
J 0
(9735 -1075);
DISPLAY 0.638298 (9735 -1075);
PAINT MONO (9735 -1075);
DISPLAY INVISIBLE (9735 -1075);
WIRE 16 -1 (10450 -600)(10450 -575);
WIRE 16 -1 (9975 -575)(10450 -575);
FORCEPROP 2 LAST SIG_NAME NC_Q95_D2
J 0
(10015 -565);
DISPLAY 0.510638 (10015 -565);
PAINT WHITE (10015 -565);
FORCEPROP 2 LASTPROP $XRERR UNIQUE?
J 0
(9735 -575);
DISPLAY 0.638298 (9735 -575);
PAINT MONO (9735 -575);
DISPLAY INVISIBLE (9735 -575);
WIRE 16 -1 (11200 -525)(12425 -525);
FORCEPROP 2 LAST SIG_NAME RST_PERST_BUF_M2_0_R_N
J 0
(11490 -515);
DISPLAY 0.702128 (11490 -515);
PAINT WHITE (11490 -515);
WIRE 16 -1 (6300 1150)(6925 1150);
FORCEPROP 2 LAST SIG_NAME LED_M2_SSD_0_ACT_N
J 0
(6315 1160);
DISPLAY 0.723404 (6315 1160);
PAINT WHITE (6315 1160);
WIRE 16 -1 (6275 3275)(5400 3275);
FORCEPROP 2 LAST SIG_NAME M2_SSD0_CLKREQ_EN_N
J 0
(5440 3285);
DISPLAY 0.553191 (5440 3285);
PAINT WHITE (5440 3285);
WIRE 16 -1 (5400 3100)(5400 3275);
WIRE 16 -1 (5400 3275)(5325 3275);
WIRE 16 -1 (7575 3725)(8075 3725);
WIRE 16 -1 (7725 3675)(8075 3675);
WIRE 16 -1 (8075 3775)(7250 3775);
WIRE 16 -1 (7725 3925)(8075 3925);
WIRE 16 -1 (9275 3125)(10075 3125);
FORCEPROP 2 LAST SIG_NAME NC_M2_0_NC16
J 0
(9465 3135);
DISPLAY 0.680851 (9465 3135);
PAINT WHITE (9465 3135);
FORCEPROP 2 LASTPROP $XRERR UNIQUE?
J 0
(10105 3125);
DISPLAY 0.638298 (10105 3125);
PAINT MONO (10105 3125);
DISPLAY INVISIBLE (10105 3125);
WIRE 16 -1 (9275 3175)(10075 3175);
FORCEPROP 2 LAST SIG_NAME NC_M2_0_NC17
J 0
(9465 3185);
DISPLAY 0.680851 (9465 3185);
PAINT WHITE (9465 3185);
FORCEPROP 2 LASTPROP $XRERR UNIQUE?
J 0
(10105 3175);
DISPLAY 0.638298 (10105 3175);
PAINT MONO (10105 3175);
DISPLAY INVISIBLE (10105 3175);
WIRE 16 -1 (10250 3200)(10450 3200);
WIRE 16 -1 (10250 3200)(10250 3425);
WIRE 16 -1 (9275 3425)(10250 3425);
FORCEPROP 2 LAST SIG_NAME FM_M2_SSD_0_PEDET
J 0
(9465 3435);
DISPLAY 0.680851 (9465 3435);
PAINT WHITE (9465 3435);
FORCEPROP 2 LASTPROP $XRERR UNIQUE?
J 0
(9225 3435);
DISPLAY 0.638298 (9225 3435);
PAINT MONO (9225 3435);
DISPLAY INVISIBLE (9225 3435);
WIRE 16 -1 (9275 3275)(10075 3275);
FORCEPROP 2 LAST SIG_NAME NC_M2_0_NC19
J 0
(9465 3285);
DISPLAY 0.680851 (9465 3285);
PAINT WHITE (9465 3285);
FORCEPROP 2 LASTPROP $XRERR UNIQUE?
J 0
(10105 3275);
DISPLAY 0.638298 (10105 3275);
PAINT MONO (10105 3275);
DISPLAY INVISIBLE (10105 3275);
WIRE 16 -1 (10525 3625)(9275 3625);
FORCEPROP 2 LAST SIG_NAME P3E_CPU1_P4_TX_C_DN<0>
J 0
(9465 3635);
DISPLAY 0.680851 (9465 3635);
PAINT WHITE (9465 3635);
WIRE 16 -1 (10525 3775)(9275 3775);
FORCEPROP 2 LAST SIG_NAME P3E_CPU1_P4_RX_DN<0>
J 0
(9465 3785);
DISPLAY 0.680851 (9465 3785);
PAINT WHITE (9465 3785);
WIRE 16 -1 (9275 3225)(10075 3225);
FORCEPROP 2 LAST SIG_NAME NC_M2_0_NC18
J 0
(9465 3235);
DISPLAY 0.680851 (9465 3235);
PAINT WHITE (9465 3235);
FORCEPROP 2 LASTPROP $XRERR UNIQUE?
J 0
(10105 3225);
DISPLAY 0.638298 (10105 3225);
PAINT MONO (10105 3225);
DISPLAY INVISIBLE (10105 3225);
WIRE 16 -1 (10525 3525)(9275 3525);
FORCEPROP 2 LAST SIG_NAME LED_M2_SSD_0_ACT_N
J 0
(9465 3535);
DISPLAY 0.680851 (9465 3535);
PAINT WHITE (9465 3535);
WIRE 16 -1 (9275 2775)(10075 2775);
FORCEPROP 2 LAST SIG_NAME NC_M2_0_NC9
J 0
(9465 2785);
DISPLAY 0.680851 (9465 2785);
PAINT WHITE (9465 2785);
FORCEPROP 2 LASTPROP $XRERR UNIQUE?
J 0
(10105 2775);
DISPLAY 0.638298 (10105 2775);
PAINT MONO (10105 2775);
DISPLAY INVISIBLE (10105 2775);
WIRE 16 -1 (9275 2725)(10075 2725);
FORCEPROP 2 LAST SIG_NAME NC_M2_0_NC8
J 0
(9465 2735);
DISPLAY 0.680851 (9465 2735);
PAINT WHITE (9465 2735);
FORCEPROP 2 LASTPROP $XRERR UNIQUE?
J 0
(10105 2725);
DISPLAY 0.638298 (10105 2725);
PAINT MONO (10105 2725);
DISPLAY INVISIBLE (10105 2725);
WIRE 16 -1 (9275 3025)(10075 3025);
FORCEPROP 2 LAST SIG_NAME NC_M2_0_NC14
J 0
(9465 3035);
DISPLAY 0.680851 (9465 3035);
PAINT WHITE (9465 3035);
FORCEPROP 2 LASTPROP $XRERR UNIQUE?
J 0
(10105 3025);
DISPLAY 0.638298 (10105 3025);
PAINT MONO (10105 3025);
DISPLAY INVISIBLE (10105 3025);
WIRE 16 -1 (9275 3075)(10075 3075);
FORCEPROP 2 LAST SIG_NAME NC_M2_0_NC15
J 0
(9465 3085);
DISPLAY 0.680851 (9465 3085);
PAINT WHITE (9465 3085);
FORCEPROP 2 LASTPROP $XRERR UNIQUE?
J 0
(10105 3075);
DISPLAY 0.638298 (10105 3075);
PAINT MONO (10105 3075);
DISPLAY INVISIBLE (10105 3075);
WIRE 16 -1 (7725 1050)(9050 1050);
FORCEPROP 2 LAST SIG_NAME PU_BUFFER_HDD_ACTIVITY
J 0
(8190 1060);
DISPLAY 0.723404 (8190 1060);
PAINT WHITE (8190 1060);
WIRE 16 -1 (6875 3125)(8075 3125);
FORCEPROP 2 LAST SIG_NAME CLK_100M_CPU1_CLK12_DP
J 0
(7165 3135);
DISPLAY 0.680851 (7165 3135);
PAINT WHITE (7165 3135);
WIRE 16 -1 (10525 3675)(9275 3675);
FORCEPROP 2 LAST SIG_NAME P3E_CPU1_P4_TX_C_DP<0>
J 0
(9465 3685);
DISPLAY 0.680851 (9465 3685);
PAINT WHITE (9465 3685);
WIRE 16 -1 (10525 3825)(9275 3825);
FORCEPROP 2 LAST SIG_NAME P3E_CPU1_P4_RX_DP<0>
J 0
(9465 3835);
DISPLAY 0.680851 (9465 3835);
PAINT WHITE (9465 3835);
WIRE 16 -1 (9275 2925)(10525 2925);
FORCEPROP 0 LAST CDS_PHYS_NET_NAME SMB_M2_P0_1V8AUX_SCL
J 0
(9465 2967);
PAINT MONO (9465 2967);
DISPLAY INVISIBLE (9465 2967);
FORCEPROP 2 LAST SIG_NAME SMB_M2_P1_1V8AUX_SCL
J 0
(9465 2935);
DISPLAY 0.680851 (9465 2935);
PAINT WHITE (9465 2935);
WIRE 16 -1 (10525 2975)(9275 2975);
FORCEPROP 0 LAST CDS_PHYS_NET_NAME SMB_M2_P0_1V8AUX_SDA
J 0
(9465 3017);
PAINT MONO (9465 3017);
DISPLAY INVISIBLE (9465 3017);
FORCEPROP 2 LAST SIG_NAME SMB_M2_P1_1V8AUX_SDA
J 0
(9465 2985);
DISPLAY 0.680851 (9465 2985);
PAINT WHITE (9465 2985);
WIRE 16 -1 (9275 2875)(10075 2875);
FORCEPROP 2 LAST SIG_NAME NC_M2_0_NC11
J 0
(9465 2885);
DISPLAY 0.680851 (9465 2885);
PAINT WHITE (9465 2885);
FORCEPROP 2 LASTPROP $XRERR UNIQUE?
J 0
(10105 2875);
DISPLAY 0.638298 (10105 2875);
PAINT MONO (10105 2875);
DISPLAY INVISIBLE (10105 2875);
WIRE 16 -1 (9275 2825)(10075 2825);
FORCEPROP 2 LAST SIG_NAME NC_M2_0_NC10
J 0
(9465 2835);
DISPLAY 0.680851 (9465 2835);
PAINT WHITE (9465 2835);
FORCEPROP 2 LASTPROP $XRERR UNIQUE?
J 0
(10105 2825);
DISPLAY 0.638298 (10105 2825);
PAINT MONO (10105 2825);
DISPLAY INVISIBLE (10105 2825);
WIRE 16 -1 (9275 2675)(10075 2675);
FORCEPROP 2 LAST SIG_NAME NC_M2_0_NC7
J 0
(9465 2685);
DISPLAY 0.680851 (9465 2685);
PAINT WHITE (9465 2685);
FORCEPROP 2 LASTPROP $XRERR UNIQUE?
J 0
(10105 2675);
DISPLAY 0.638298 (10105 2675);
PAINT MONO (10105 2675);
DISPLAY INVISIBLE (10105 2675);
WIRE 16 -1 (10675 -425)(10675 -525);
WIRE 16 -1 (10675 -525)(11000 -525);
WIRE 16 -1 (7950 -525)(10675 -525);
FORCEPROP 0 LAST CDS_PHYS_NET_NAME RST_PCIE_PCH_DEV_BUF_M2_0_PERST
J 0
(7975 -483);
PAINT MONO (7975 -483);
DISPLAY INVISIBLE (7975 -483);
FORCEPROP 0 LAST SIG_NAME RST_PERST_BUF_M2_0_N
J 0
(8140 -515);
DISPLAY 0.702128 (8140 -515);
PAINT WHITE (8140 -515);
FORCEPROP 2 LASTPROP $XRERR UNIQUE?
J 0
(7900 -515);
DISPLAY 0.638298 (7900 -515);
PAINT MONO (7900 -515);
DISPLAY INVISIBLE (7900 -515);
WIRE 16 -1 (7025 3225)(8075 3225);
FORCEPROP 0 LAST CDS_PHYS_NET_NAME M2_0_PEWAKE_N
J 0
(7215 3267);
PAINT MONO (7215 3267);
DISPLAY INVISIBLE (7215 3267);
FORCEPROP 2 LAST SIG_NAME M2_0_PEWAKE_N
J 0
(7365 3235);
DISPLAY 0.680851 (7365 3235);
PAINT WHITE (7365 3235);
FORCEPROP 2 LASTPROP $XRERR UNIQUE?
J 0
(7125 3235);
DISPLAY 0.638298 (7125 3235);
PAINT MONO (7125 3235);
DISPLAY INVISIBLE (7125 3235);
WIRE 16 -1 (6875 3075)(8075 3075);
FORCEPROP 2 LAST SIG_NAME CLK_100M_CPU1_CLK12_DN
J 0
(7165 3085);
DISPLAY 0.680851 (7165 3085);
PAINT WHITE (7165 3085);
WIRE 16 -1 (8075 2325)(6925 2325);
FORCEPROP 2 LAST SIG_NAME PCIE_M2_SSD0_PRSNT_N
J 0
(7165 2335);
DISPLAY 0.680851 (7165 2335);
PAINT WHITE (7165 2335);
WIRE 16 -1 (6925 2525)(6925 2325);
WIRE 16 -1 (6925 2325)(6875 2325);
WIRE 16 -1 (6150 -525)(7300 -525);
FORCEPROP 0 LAST CDS_PHYS_NET_NAME RST_PCIE_PCH_DEV_PERST_M2_R_N
J 0
(6175 -483);
PAINT MONO (6175 -483);
DISPLAY INVISIBLE (6175 -483);
FORCEPROP 0 LAST SIG_NAME RST_PERST_M2_0_N
J 0
(6165 -515);
DISPLAY 0.702128 (6165 -515);
PAINT WHITE (6165 -515);
WIRE 16 -1 (6150 -425)(7300 -425);
WIRE 16 -1 (7400 3825)(8075 3825);
WIRE 16 -1 (7725 4175)(8075 4175);
WIRE 16 -1 (6475 3275)(6925 3275);
WIRE 16 -1 (6925 3275)(8075 3275);
FORCEPROP 2 LAST SIG_NAME M2_SSD0_CLKREQ_EN_N_BUF
J 0
(7165 3285);
DISPLAY 0.702128 (7165 3285);
PAINT WHITE (7165 3285);
FORCEPROP 2 LASTPROP $XRERR UNIQUE?
J 0
(6925 3285);
DISPLAY 0.638298 (6925 3285);
PAINT MONO (6925 3285);
DISPLAY INVISIBLE (6925 3285);
WIRE 16 -1 (6925 3750)(6925 3275);
DOT 1 (10675 175);
DOT 1 (11625 3950);
DOT 1 (7925 2575);
DOT 1 (7925 2225);
DOT 1 (7925 2925);
DOT 1 (9425 4325);
DOT 1 (9425 3975);
DOT 1 (9425 4075);
DOT 1 (6925 3275);
DOT 1 (10250 1100);
DOT 1 (8000 -475);
DOT 1 (8575 -175);
DOT 1 (10675 -525);
DOT 1 (5400 3275);
DOT 1 (7600 1150);
DOT 1 (6925 2325);
DOT 1 (7925 2175);
DOT 1 (7925 2375);
DOT 1 (7925 2425);
DOT 1 (7925 2475);
DOT 1 (7925 2525);
DOT 1 (7925 2625);
DOT 1 (7925 2775);
DOT 1 (7925 2825);
DOT 1 (7925 2875);
DOT 1 (9300 1650);
DOT 1 (12025 3950);
DOT 1 (9425 4025);
DOT 1 (9425 4175);
DOT 1 (9425 4125);
DOT 1 (9425 4275);
DOT 1 (9425 4225);
DOT 1 (11225 4400);
DOT 1 (11625 4400);
DOT 1 (12025 4400);
DOT 1 (12425 3950);
DOT 1 (12825 3950);
DOT 1 (13225 3950);
DOT 1 (12425 4400);
DOT 1 (12825 4400);
DOT 1 (7925 2675);
DOT 1 (7925 2725);
FORCENOTE
TO SCM HDD ACTIVITY LED
(10675 1475) 0;
DISPLAY LEFT (10675 1475);
DISPLAY 1.723404 (10675 1475);
PAINT WHITE (10675 1475);
QUIT
